FILE_TYPE = MACRO_DRAWING;
SET COLOR_WIRE YELLOW;
SET COLOR_PROP MONO;
SET COLOR_DOT WHITE;
SET COLOR_ARC YELLOW;
SET COLOR_BODY GREEN;
SET COLOR_NOTE MONO;
SET PROP_DISPLAY VALUE;
SET PAGE_NUMBER P138;
FORCEADD OFFPAGE..1
(-1350 3050);
FORCEPROP 2 LAST $XR0 120 
J 0
(-1602 3050);
DISPLAY 0.638298 (-1602 3050);
PAINT MONO (-1602 3050);
FORCEPROP 2 LASTPIN (-1300 3050) SIG_NAME SMB_SENSOR_STBY_LVC3_SCL_R1
J 0
(-1300 3060);
DISPLAY 0.617021 (-1300 3060);
PAINT ORANGE (-1300 3060);
FORCEPROP 2 LAST PATH I100
J 0
(-1300 3125);
DISPLAY 1.021277 (-1300 3125);
PAINT ORANGE (-1300 3125);
DISPLAY INVISIBLE (-1300 3125);
FORCEPROP 2 LAST CDS_LIB mstr_standard
J 0
(-1350 3050);
PAINT ORANGE (-1350 3050);
DISPLAY INVISIBLE (-1350 3050);
FORCEPROP 1 LAST OFFPAGE TRUE
J 0
(-1025 2925);
DISPLAY 0.872340 (-1025 2925);
PAINT GREEN (-1025 2925);
DISPLAY INVISIBLE (-1025 2925);
FORCEPROP 1 LAST COMMENT_BODY TRUE
J 0
(-1225 2950);
DISPLAY 0.872340 (-1225 2950);
PAINT GREEN (-1225 2950);
DISPLAY INVISIBLE (-1225 2950);
FORCEADD OFFPAGE..6
(-1325 3225);
FORCEPROP 2 LAST $XR0 120 
J 0
(-1635 3225);
DISPLAY 0.638298 (-1635 3225);
PAINT MONO (-1635 3225);
FORCEPROP 2 LASTPIN (-1275 3225) SIG_NAME SMB_SENSOR_STBY_LVC3_SDA_R1
J 0
(-1300 3235);
DISPLAY 0.617021 (-1300 3235);
PAINT ORANGE (-1300 3235);
FORCEPROP 1 LAST OFFPAGE TRUE
J 0
(-1000 3100);
DISPLAY 0.872340 (-1000 3100);
PAINT GREEN (-1000 3100);
DISPLAY INVISIBLE (-1000 3100);
FORCEPROP 1 LAST COMMENT_BODY TRUE
J 0
(-1225 3150);
DISPLAY 0.872340 (-1225 3150);
PAINT GREEN (-1225 3150);
DISPLAY INVISIBLE (-1225 3150);
FORCEPROP 2 LAST CDS_LIB mstr_standard
J 0
(-1325 3225);
PAINT ORANGE (-1325 3225);
DISPLAY INVISIBLE (-1325 3225);
FORCEPROP 2 LAST PATH I103
J 0
(-1600 3275);
DISPLAY 1.021277 (-1600 3275);
PAINT ORANGE (-1600 3275);
DISPLAY INVISIBLE (-1600 3275);
FORCEADD OFFPAGE..6
(-4825 4625);
FORCEPROP 2 LAST $XR0 119 
J 0
(-5105 4625);
DISPLAY 0.638298 (-5105 4625);
PAINT MONO (-5105 4625);
FORCEPROP 1 LAST OFFPAGE TRUE
J 0
(-4500 4500);
DISPLAY 0.872340 (-4500 4500);
PAINT GREEN (-4500 4500);
DISPLAY INVISIBLE (-4500 4500);
FORCEPROP 2 LAST CDS_LIB mstr_standard
J 0
(-4825 4625);
PAINT ORANGE (-4825 4625);
DISPLAY INVISIBLE (-4825 4625);
FORCEPROP 2 LAST PATH I104
J 0
(-5100 4675);
DISPLAY 1.021277 (-5100 4675);
PAINT ORANGE (-5100 4675);
DISPLAY INVISIBLE (-5100 4675);
FORCEPROP 1 LAST COMMENT_BODY TRUE
J 0
(-4725 4550);
DISPLAY 0.872340 (-4725 4550);
PAINT GREEN (-4725 4550);
DISPLAY INVISIBLE (-4725 4550);
FORCEADD OFFPAGE..1
(-4850 4475);
FORCEPROP 2 LAST $XR0 119 
J 0
(-5102 4475);
DISPLAY 0.638298 (-5102 4475);
PAINT MONO (-5102 4475);
FORCEPROP 1 LAST OFFPAGE TRUE
J 0
(-4525 4350);
DISPLAY 0.872340 (-4525 4350);
PAINT GREEN (-4525 4350);
DISPLAY INVISIBLE (-4525 4350);
FORCEPROP 2 LAST CDS_LIB mstr_standard
J 0
(-4850 4475);
PAINT ORANGE (-4850 4475);
DISPLAY INVISIBLE (-4850 4475);
FORCEPROP 1 LAST COMMENT_BODY TRUE
J 0
(-4725 4375);
DISPLAY 0.872340 (-4725 4375);
PAINT GREEN (-4725 4375);
DISPLAY INVISIBLE (-4725 4375);
FORCEPROP 2 LAST PATH I105
J 0
(-4800 4550);
DISPLAY 1.021277 (-4800 4550);
PAINT ORANGE (-4800 4550);
DISPLAY INVISIBLE (-4800 4550);
FORCEADD OFFPAGE..6
(-4825 3700);
FORCEPROP 2 LASTPIN (-4775 3700) SIG_NAME SMB_HOST_STBY_LVC3_SDA_R1
J 0
(-4800 3710);
DISPLAY 0.617021 (-4800 3710);
PAINT ORANGE (-4800 3710);
FORCEPROP 2 LAST $XR0 119 
J 0
(-5105 3700);
DISPLAY 0.638298 (-5105 3700);
PAINT MONO (-5105 3700);
FORCEPROP 1 LAST OFFPAGE TRUE
J 0
(-4500 3575);
DISPLAY 0.872340 (-4500 3575);
PAINT GREEN (-4500 3575);
DISPLAY INVISIBLE (-4500 3575);
FORCEPROP 2 LAST CDS_LIB mstr_standard
J 0
(-4825 3700);
PAINT ORANGE (-4825 3700);
DISPLAY INVISIBLE (-4825 3700);
FORCEPROP 1 LAST COMMENT_BODY TRUE
J 0
(-4725 3625);
DISPLAY 0.872340 (-4725 3625);
PAINT GREEN (-4725 3625);
DISPLAY INVISIBLE (-4725 3625);
FORCEPROP 2 LAST PATH I108
J 0
(-5100 3750);
DISPLAY 1.021277 (-5100 3750);
PAINT ORANGE (-5100 3750);
DISPLAY INVISIBLE (-5100 3750);
FORCEADD OFFPAGE..1
(-4850 3550);
FORCEPROP 2 LAST $XR0 119 
J 0
(-5102 3550);
DISPLAY 0.638298 (-5102 3550);
PAINT MONO (-5102 3550);
FORCEPROP 1 LAST OFFPAGE TRUE
J 0
(-4525 3425);
DISPLAY 0.872340 (-4525 3425);
PAINT GREEN (-4525 3425);
DISPLAY INVISIBLE (-4525 3425);
FORCEPROP 2 LAST PATH I111
J 0
(-4800 3625);
DISPLAY 1.021277 (-4800 3625);
PAINT ORANGE (-4800 3625);
DISPLAY INVISIBLE (-4800 3625);
FORCEPROP 2 LAST CDS_LIB mstr_standard
J 0
(-4850 3550);
PAINT ORANGE (-4850 3550);
DISPLAY INVISIBLE (-4850 3550);
FORCEPROP 1 LAST COMMENT_BODY TRUE
J 0
(-4725 3450);
DISPLAY 0.872340 (-4725 3450);
PAINT GREEN (-4725 3450);
DISPLAY INVISIBLE (-4725 3450);
FORCEADD OFFPAGE..1
(-1350 2125);
FORCEPROP 2 LASTPIN (-1300 2125) SIG_NAME SMB_VR_STBY_LVC3_SCL_R1
J 0
(-1300 2135);
DISPLAY 0.617021 (-1300 2135);
PAINT ORANGE (-1300 2135);
FORCEPROP 2 LAST $XR0 120 
J 0
(-1602 2125);
DISPLAY 0.638298 (-1602 2125);
PAINT MONO (-1602 2125);
FORCEPROP 2 LAST PATH I114
J 0
(-1300 2200);
DISPLAY 1.021277 (-1300 2200);
PAINT ORANGE (-1300 2200);
DISPLAY INVISIBLE (-1300 2200);
FORCEPROP 2 LAST CDS_LIB mstr_standard
J 0
(-1350 2125);
PAINT ORANGE (-1350 2125);
DISPLAY INVISIBLE (-1350 2125);
FORCEPROP 1 LAST COMMENT_BODY TRUE
J 0
(-1225 2025);
DISPLAY 0.872340 (-1225 2025);
PAINT GREEN (-1225 2025);
DISPLAY INVISIBLE (-1225 2025);
FORCEPROP 1 LAST OFFPAGE TRUE
J 0
(-1025 2000);
DISPLAY 0.872340 (-1025 2000);
PAINT GREEN (-1025 2000);
DISPLAY INVISIBLE (-1025 2000);
FORCEADD OFFPAGE..6
(-1325 2275);
FORCEPROP 2 LASTPIN (-1275 2275) SIG_NAME SMB_VR_STBY_LVC3_SDA_R1
J 0
(-1300 2285);
DISPLAY 0.617021 (-1300 2285);
PAINT ORANGE (-1300 2285);
FORCEPROP 2 LAST $XR0 120 
J 0
(-1635 2275);
DISPLAY 0.638298 (-1635 2275);
PAINT MONO (-1635 2275);
FORCEPROP 1 LAST OFFPAGE TRUE
J 0
(-1000 2150);
DISPLAY 0.872340 (-1000 2150);
PAINT GREEN (-1000 2150);
DISPLAY INVISIBLE (-1000 2150);
FORCEPROP 1 LAST COMMENT_BODY TRUE
J 0
(-1225 2200);
DISPLAY 0.872340 (-1225 2200);
PAINT GREEN (-1225 2200);
DISPLAY INVISIBLE (-1225 2200);
FORCEPROP 2 LAST CDS_LIB mstr_standard
J 0
(-1325 2275);
PAINT ORANGE (-1325 2275);
DISPLAY INVISIBLE (-1325 2275);
FORCEPROP 2 LAST PATH I115
J 0
(-1600 2325);
DISPLAY 1.021277 (-1600 2325);
PAINT ORANGE (-1600 2325);
DISPLAY INVISIBLE (-1600 2325);
FORCEADD OFFPAGE..6
(-4800 2650);
FORCEPROP 2 LASTPIN (-4750 2650) SIG_NAME SMB_SLOTX24_STBY_LVC3_SDA_R1
J 0
(-4775 2660);
DISPLAY 0.617021 (-4775 2660);
PAINT ORANGE (-4775 2660);
FORCEPROP 2 LAST $XR0 119 
J 0
(-5080 2650);
DISPLAY 0.638298 (-5080 2650);
PAINT MONO (-5080 2650);
FORCEPROP 1 LAST OFFPAGE TRUE
J 0
(-4475 2525);
DISPLAY 0.872340 (-4475 2525);
PAINT GREEN (-4475 2525);
DISPLAY INVISIBLE (-4475 2525);
FORCEPROP 2 LAST CDS_LIB mstr_standard
J 0
(-4800 2650);
PAINT ORANGE (-4800 2650);
DISPLAY INVISIBLE (-4800 2650);
FORCEPROP 1 LAST COMMENT_BODY TRUE
J 0
(-4700 2575);
DISPLAY 0.872340 (-4700 2575);
PAINT GREEN (-4700 2575);
DISPLAY INVISIBLE (-4700 2575);
FORCEPROP 2 LAST PATH I122
J 0
(-5075 2700);
DISPLAY 1.021277 (-5075 2700);
PAINT ORANGE (-5075 2700);
DISPLAY INVISIBLE (-5075 2700);
FORCEADD OFFPAGE..1
(-4825 2500);
FORCEPROP 2 LASTPIN (-4775 2500) SIG_NAME SMB_SLOTX24_STBY_LVC3_SCL_R1
J 0
(-4775 2510);
DISPLAY 0.617021 (-4775 2510);
PAINT ORANGE (-4775 2510);
FORCEPROP 2 LAST $XR0 119 
J 0
(-5107 2500);
DISPLAY 0.638298 (-5107 2500);
PAINT MONO (-5107 2500);
FORCEPROP 1 LAST OFFPAGE TRUE
J 0
(-4500 2375);
DISPLAY 0.872340 (-4500 2375);
PAINT GREEN (-4500 2375);
DISPLAY INVISIBLE (-4500 2375);
FORCEPROP 2 LAST PATH I123
J 0
(-4775 2575);
DISPLAY 1.021277 (-4775 2575);
PAINT ORANGE (-4775 2575);
DISPLAY INVISIBLE (-4775 2575);
FORCEPROP 2 LAST CDS_LIB mstr_standard
J 0
(-4825 2500);
PAINT ORANGE (-4825 2500);
DISPLAY INVISIBLE (-4825 2500);
FORCEPROP 1 LAST COMMENT_BODY TRUE
J 0
(-4700 2400);
DISPLAY 0.872340 (-4700 2400);
PAINT GREEN (-4700 2400);
DISPLAY INVISIBLE (-4700 2400);
FORCEADD OFFPAGE..1
(-4825 1625);
FORCEPROP 2 LASTPIN (-4775 1625) SIG_NAME SMB_LAN_STBY_LVC3_SCL_R1
J 0
(-4775 1635);
DISPLAY 0.617021 (-4775 1635);
PAINT ORANGE (-4775 1635);
FORCEPROP 2 LAST $XR0 120 
J 0
(-5107 1625);
DISPLAY 0.638298 (-5107 1625);
PAINT MONO (-5107 1625);
FORCEPROP 1 LAST OFFPAGE TRUE
J 0
(-4500 1500);
DISPLAY 0.872340 (-4500 1500);
PAINT GREEN (-4500 1500);
DISPLAY INVISIBLE (-4500 1500);
FORCEPROP 2 LAST PATH I126
J 0
(-4775 1700);
DISPLAY 1.021277 (-4775 1700);
PAINT ORANGE (-4775 1700);
DISPLAY INVISIBLE (-4775 1700);
FORCEPROP 2 LAST CDS_LIB mstr_standard
J 0
(-4825 1625);
PAINT ORANGE (-4825 1625);
DISPLAY INVISIBLE (-4825 1625);
FORCEPROP 1 LAST COMMENT_BODY TRUE
J 0
(-4700 1525);
DISPLAY 0.872340 (-4700 1525);
PAINT GREEN (-4700 1525);
DISPLAY INVISIBLE (-4700 1525);
FORCEADD OFFPAGE..6
(-4800 1775);
FORCEPROP 2 LAST $XR0 120 
J 0
(-5080 1775);
DISPLAY 0.638298 (-5080 1775);
PAINT MONO (-5080 1775);
FORCEPROP 1 LAST OFFPAGE TRUE
J 0
(-4475 1650);
DISPLAY 0.872340 (-4475 1650);
PAINT GREEN (-4475 1650);
DISPLAY INVISIBLE (-4475 1650);
FORCEPROP 2 LAST PATH I127
J 0
(-4750 1850);
DISPLAY 1.021277 (-4750 1850);
PAINT ORANGE (-4750 1850);
DISPLAY INVISIBLE (-4750 1850);
FORCEPROP 2 LAST CDS_LIB mstr_standard
J 0
(-4800 1775);
PAINT ORANGE (-4800 1775);
DISPLAY INVISIBLE (-4800 1775);
FORCEPROP 1 LAST COMMENT_BODY TRUE
J 0
(-4700 1700);
DISPLAY 0.872340 (-4700 1700);
PAINT GREEN (-4700 1700);
DISPLAY INVISIBLE (-4700 1700);
FORCEADD P3V3_STBY..1
(500 4725);
FORCEPROP 3 LASTPIN (500 4675) SIG_NAME P3V3_STBY\g
J 0
(510 4685);
DISPLAY 0.659574 (510 4685);
PAINT MONO (510 4685);
DISPLAY INVISIBLE (510 4685);
FORCEPROP 2 LAST CDS_LIB mstr_symbols
J 0
(500 4725);
PAINT ORANGE (500 4725);
DISPLAY INVISIBLE (500 4725);
FORCEPROP 1 LAST PATH I138
J 0
(545 4727);
DISPLAY 0.340426 (545 4727);
PAINT GREEN (545 4727);
DISPLAY INVISIBLE (545 4727);
FORCEPROP 1 LAST SIZE 1B
J 0
(545 4747);
DISPLAY 0.340426 (545 4747);
PAINT GREEN (545 4747);
DISPLAY INVISIBLE (545 4747);
FORCEPROP 1 LAST BODY_TYPE PLUMBING
J 0
(455 4682);
DISPLAY 0.340426 (455 4682);
PAINT GREEN (455 4682);
DISPLAY INVISIBLE (455 4682);
FORCEPROP 1 LAST VOLTAGE 3.3V
J 0
(455 4682);
DISPLAY 0.340426 (455 4682);
PAINT SKYBLUE (455 4682);
DISPLAY INVISIBLE (455 4682);
FORCEPROP 1 LAST HDL_POWER P3V3_STBY
J 0
(200 4600);
DISPLAY 0.872340 (200 4600);
PAINT ORANGE (200 4600);
DISPLAY INVISIBLE (200 4600);
FORCEADD P3V3_STBY..1
(850 4675);
FORCEPROP 3 LASTPIN (850 4625) SIG_NAME P3V3_STBY\g
J 0
(860 4635);
DISPLAY 0.659574 (860 4635);
PAINT MONO (860 4635);
DISPLAY INVISIBLE (860 4635);
FORCEPROP 1 LAST PATH I139
J 0
(895 4677);
DISPLAY 0.340426 (895 4677);
PAINT GREEN (895 4677);
DISPLAY INVISIBLE (895 4677);
FORCEPROP 1 LAST BODY_TYPE PLUMBING
J 0
(805 4632);
DISPLAY 0.340426 (805 4632);
PAINT GREEN (805 4632);
DISPLAY INVISIBLE (805 4632);
FORCEPROP 1 LAST SIZE 1B
J 0
(895 4697);
DISPLAY 0.340426 (895 4697);
PAINT GREEN (895 4697);
DISPLAY INVISIBLE (895 4697);
FORCEPROP 2 LAST CDS_LIB mstr_symbols
J 0
(850 4675);
PAINT ORANGE (850 4675);
DISPLAY INVISIBLE (850 4675);
FORCEPROP 1 LAST VOLTAGE 3.3V
J 0
(805 4632);
DISPLAY 0.340426 (805 4632);
PAINT SKYBLUE (805 4632);
DISPLAY INVISIBLE (805 4632);
FORCEPROP 1 LAST HDL_POWER P3V3_STBY
J 0
(550 4550);
DISPLAY 0.872340 (550 4550);
PAINT ORANGE (550 4550);
DISPLAY INVISIBLE (550 4550);
FORCEADD P3V3_STBY..1
(500 2825);
FORCEPROP 3 LASTPIN (500 2775) SIG_NAME P3V3_STBY\g
J 0
(510 2785);
DISPLAY 0.659574 (510 2785);
PAINT MONO (510 2785);
DISPLAY INVISIBLE (510 2785);
FORCEPROP 1 LAST PATH I140
J 0
(545 2827);
DISPLAY 0.340426 (545 2827);
PAINT GREEN (545 2827);
DISPLAY INVISIBLE (545 2827);
FORCEPROP 1 LAST SIZE 1B
J 0
(545 2847);
DISPLAY 0.340426 (545 2847);
PAINT GREEN (545 2847);
DISPLAY INVISIBLE (545 2847);
FORCEPROP 1 LAST BODY_TYPE PLUMBING
J 0
(455 2782);
DISPLAY 0.340426 (455 2782);
PAINT GREEN (455 2782);
DISPLAY INVISIBLE (455 2782);
FORCEPROP 2 LAST CDS_LIB mstr_symbols
J 0
(500 2825);
PAINT ORANGE (500 2825);
DISPLAY INVISIBLE (500 2825);
FORCEPROP 1 LAST VOLTAGE 3.3V
J 0
(455 2782);
DISPLAY 0.340426 (455 2782);
PAINT SKYBLUE (455 2782);
DISPLAY INVISIBLE (455 2782);
FORCEPROP 1 LAST HDL_POWER P3V3_STBY
J 0
(200 2700);
DISPLAY 0.872340 (200 2700);
PAINT ORANGE (200 2700);
DISPLAY INVISIBLE (200 2700);
FORCEADD P3V3_STBY..1
(875 2775);
FORCEPROP 3 LASTPIN (875 2725) SIG_NAME P3V3_STBY\g
J 0
(885 2735);
DISPLAY 0.659574 (885 2735);
PAINT MONO (885 2735);
DISPLAY INVISIBLE (885 2735);
FORCEPROP 2 LAST CDS_LIB mstr_symbols
J 0
(875 2775);
PAINT ORANGE (875 2775);
DISPLAY INVISIBLE (875 2775);
FORCEPROP 1 LAST PATH I141
J 0
(920 2777);
DISPLAY 0.340426 (920 2777);
PAINT GREEN (920 2777);
DISPLAY INVISIBLE (920 2777);
FORCEPROP 1 LAST SIZE 1B
J 0
(920 2797);
DISPLAY 0.340426 (920 2797);
PAINT GREEN (920 2797);
DISPLAY INVISIBLE (920 2797);
FORCEPROP 1 LAST BODY_TYPE PLUMBING
J 0
(830 2732);
DISPLAY 0.340426 (830 2732);
PAINT GREEN (830 2732);
DISPLAY INVISIBLE (830 2732);
FORCEPROP 1 LAST VOLTAGE 3.3V
J 0
(830 2732);
DISPLAY 0.340426 (830 2732);
PAINT SKYBLUE (830 2732);
DISPLAY INVISIBLE (830 2732);
FORCEPROP 1 LAST HDL_POWER P3V3_STBY
J 0
(575 2650);
DISPLAY 0.872340 (575 2650);
PAINT ORANGE (575 2650);
DISPLAY INVISIBLE (575 2650);
FORCEADD P3V3_STBY..1
(-3175 5200);
FORCEPROP 3 LASTPIN (-3175 5150) SIG_NAME P3V3_STBY\g
J 0
(-3165 5160);
DISPLAY 0.659574 (-3165 5160);
PAINT MONO (-3165 5160);
DISPLAY INVISIBLE (-3165 5160);
FORCEPROP 1 LAST SIZE 1B
J 0
(-3130 5222);
DISPLAY 0.340426 (-3130 5222);
PAINT GREEN (-3130 5222);
DISPLAY INVISIBLE (-3130 5222);
FORCEPROP 2 LAST CDS_LIB mstr_symbols
J 0
(-3175 5200);
PAINT ORANGE (-3175 5200);
DISPLAY INVISIBLE (-3175 5200);
FORCEPROP 1 LAST BODY_TYPE PLUMBING
J 0
(-3220 5157);
DISPLAY 0.340426 (-3220 5157);
PAINT GREEN (-3220 5157);
DISPLAY INVISIBLE (-3220 5157);
FORCEPROP 1 LAST PATH I144
J 0
(-3130 5202);
DISPLAY 0.340426 (-3130 5202);
PAINT GREEN (-3130 5202);
DISPLAY INVISIBLE (-3130 5202);
FORCEPROP 1 LAST VOLTAGE 3.3V
J 0
(-3220 5157);
DISPLAY 0.340426 (-3220 5157);
PAINT SKYBLUE (-3220 5157);
DISPLAY INVISIBLE (-3220 5157);
FORCEPROP 1 LAST HDL_POWER P3V3_STBY
J 0
(-3475 5075);
DISPLAY 0.872340 (-3475 5075);
PAINT ORANGE (-3475 5075);
DISPLAY INVISIBLE (-3475 5075);
FORCEADD P3V3_STBY..1
(-2775 5150);
FORCEPROP 3 LASTPIN (-2775 5100) SIG_NAME P3V3_STBY\g
J 0
(-2765 5110);
DISPLAY 0.659574 (-2765 5110);
PAINT MONO (-2765 5110);
DISPLAY INVISIBLE (-2765 5110);
FORCEPROP 1 LAST PATH I145
J 0
(-2730 5152);
DISPLAY 0.340426 (-2730 5152);
PAINT GREEN (-2730 5152);
DISPLAY INVISIBLE (-2730 5152);
FORCEPROP 2 LAST CDS_LIB mstr_symbols
J 0
(-2775 5150);
PAINT ORANGE (-2775 5150);
DISPLAY INVISIBLE (-2775 5150);
FORCEPROP 1 LAST SIZE 1B
J 0
(-2730 5172);
DISPLAY 0.340426 (-2730 5172);
PAINT GREEN (-2730 5172);
DISPLAY INVISIBLE (-2730 5172);
FORCEPROP 1 LAST BODY_TYPE PLUMBING
J 0
(-2820 5107);
DISPLAY 0.340426 (-2820 5107);
PAINT GREEN (-2820 5107);
DISPLAY INVISIBLE (-2820 5107);
FORCEPROP 1 LAST VOLTAGE 3.3V
J 0
(-2820 5107);
DISPLAY 0.340426 (-2820 5107);
PAINT SKYBLUE (-2820 5107);
DISPLAY INVISIBLE (-2820 5107);
FORCEPROP 1 LAST HDL_POWER P3V3_STBY
J 0
(-3075 5025);
DISPLAY 0.872340 (-3075 5025);
PAINT ORANGE (-3075 5025);
DISPLAY INVISIBLE (-3075 5025);
FORCEADD P3V3_STBY..1
(-3175 4250);
FORCEPROP 3 LASTPIN (-3175 4200) SIG_NAME P3V3_STBY\g
J 0
(-3165 4210);
DISPLAY 0.659574 (-3165 4210);
PAINT MONO (-3165 4210);
DISPLAY INVISIBLE (-3165 4210);
FORCEPROP 1 LAST PATH I146
J 0
(-3130 4252);
DISPLAY 0.340426 (-3130 4252);
PAINT GREEN (-3130 4252);
DISPLAY INVISIBLE (-3130 4252);
FORCEPROP 1 LAST SIZE 1B
J 0
(-3130 4272);
DISPLAY 0.340426 (-3130 4272);
PAINT GREEN (-3130 4272);
DISPLAY INVISIBLE (-3130 4272);
FORCEPROP 2 LAST CDS_LIB mstr_symbols
J 0
(-3175 4250);
PAINT ORANGE (-3175 4250);
DISPLAY INVISIBLE (-3175 4250);
FORCEPROP 1 LAST BODY_TYPE PLUMBING
J 0
(-3220 4207);
DISPLAY 0.340426 (-3220 4207);
PAINT GREEN (-3220 4207);
DISPLAY INVISIBLE (-3220 4207);
FORCEPROP 1 LAST VOLTAGE 3.3V
J 0
(-3220 4207);
DISPLAY 0.340426 (-3220 4207);
PAINT SKYBLUE (-3220 4207);
DISPLAY INVISIBLE (-3220 4207);
FORCEPROP 1 LAST HDL_POWER P3V3_STBY
J 0
(-3475 4125);
DISPLAY 0.872340 (-3475 4125);
PAINT ORANGE (-3475 4125);
DISPLAY INVISIBLE (-3475 4125);
FORCEADD P3V3_STBY..1
(-2775 4200);
FORCEPROP 3 LASTPIN (-2775 4150) SIG_NAME P3V3_STBY\g
J 0
(-2765 4160);
DISPLAY 0.659574 (-2765 4160);
PAINT MONO (-2765 4160);
DISPLAY INVISIBLE (-2765 4160);
FORCEPROP 1 LAST SIZE 1B
J 0
(-2730 4222);
DISPLAY 0.340426 (-2730 4222);
PAINT GREEN (-2730 4222);
DISPLAY INVISIBLE (-2730 4222);
FORCEPROP 2 LAST CDS_LIB mstr_symbols
J 0
(-2775 4200);
PAINT ORANGE (-2775 4200);
DISPLAY INVISIBLE (-2775 4200);
FORCEPROP 1 LAST PATH I147
J 0
(-2730 4202);
DISPLAY 0.340426 (-2730 4202);
PAINT GREEN (-2730 4202);
DISPLAY INVISIBLE (-2730 4202);
FORCEPROP 1 LAST BODY_TYPE PLUMBING
J 0
(-2820 4157);
DISPLAY 0.340426 (-2820 4157);
PAINT GREEN (-2820 4157);
DISPLAY INVISIBLE (-2820 4157);
FORCEPROP 1 LAST VOLTAGE 3.3V
J 0
(-2820 4157);
DISPLAY 0.340426 (-2820 4157);
PAINT SKYBLUE (-2820 4157);
DISPLAY INVISIBLE (-2820 4157);
FORCEPROP 1 LAST HDL_POWER P3V3_STBY
J 0
(-3075 4075);
DISPLAY 0.872340 (-3075 4075);
PAINT ORANGE (-3075 4075);
DISPLAY INVISIBLE (-3075 4075);
FORCEADD P3V3_STBY..1
(-3150 3200);
FORCEPROP 3 LASTPIN (-3150 3150) SIG_NAME P3V3_STBY\g
J 0
(-3140 3160);
DISPLAY 0.659574 (-3140 3160);
PAINT MONO (-3140 3160);
DISPLAY INVISIBLE (-3140 3160);
FORCEPROP 1 LAST PATH I148
J 0
(-3105 3202);
DISPLAY 0.340426 (-3105 3202);
PAINT GREEN (-3105 3202);
DISPLAY INVISIBLE (-3105 3202);
FORCEPROP 1 LAST SIZE 1B
J 0
(-3105 3222);
DISPLAY 0.340426 (-3105 3222);
PAINT GREEN (-3105 3222);
DISPLAY INVISIBLE (-3105 3222);
FORCEPROP 2 LAST CDS_LIB mstr_symbols
J 0
(-3150 3200);
PAINT ORANGE (-3150 3200);
DISPLAY INVISIBLE (-3150 3200);
FORCEPROP 1 LAST BODY_TYPE PLUMBING
J 0
(-3195 3157);
DISPLAY 0.340426 (-3195 3157);
PAINT GREEN (-3195 3157);
DISPLAY INVISIBLE (-3195 3157);
FORCEPROP 1 LAST VOLTAGE 3.3V
J 0
(-3195 3157);
DISPLAY 0.340426 (-3195 3157);
PAINT SKYBLUE (-3195 3157);
DISPLAY INVISIBLE (-3195 3157);
FORCEPROP 1 LAST HDL_POWER P3V3_STBY
J 0
(-3450 3075);
DISPLAY 0.872340 (-3450 3075);
PAINT ORANGE (-3450 3075);
DISPLAY INVISIBLE (-3450 3075);
FORCEADD P3V3_STBY..1
(-2750 3150);
FORCEPROP 3 LASTPIN (-2750 3100) SIG_NAME P3V3_STBY\g
J 0
(-2740 3110);
DISPLAY 0.659574 (-2740 3110);
PAINT MONO (-2740 3110);
DISPLAY INVISIBLE (-2740 3110);
FORCEPROP 1 LAST PATH I149
J 0
(-2705 3152);
DISPLAY 0.340426 (-2705 3152);
PAINT GREEN (-2705 3152);
DISPLAY INVISIBLE (-2705 3152);
FORCEPROP 1 LAST BODY_TYPE PLUMBING
J 0
(-2795 3107);
DISPLAY 0.340426 (-2795 3107);
PAINT GREEN (-2795 3107);
DISPLAY INVISIBLE (-2795 3107);
FORCEPROP 2 LAST CDS_LIB mstr_symbols
J 0
(-2750 3150);
PAINT ORANGE (-2750 3150);
DISPLAY INVISIBLE (-2750 3150);
FORCEPROP 1 LAST SIZE 1B
J 0
(-2705 3172);
DISPLAY 0.340426 (-2705 3172);
PAINT GREEN (-2705 3172);
DISPLAY INVISIBLE (-2705 3172);
FORCEPROP 1 LAST VOLTAGE 3.3V
J 0
(-2795 3107);
DISPLAY 0.340426 (-2795 3107);
PAINT SKYBLUE (-2795 3107);
DISPLAY INVISIBLE (-2795 3107);
FORCEPROP 1 LAST HDL_POWER P3V3_STBY
J 0
(-3050 3025);
DISPLAY 0.872340 (-3050 3025);
PAINT ORANGE (-3050 3025);
DISPLAY INVISIBLE (-3050 3025);
FORCEADD P3V3_STBY..1
(-3150 2300);
FORCEPROP 3 LASTPIN (-3150 2250) SIG_NAME P3V3_STBY\g
J 0
(-3140 2260);
DISPLAY 0.659574 (-3140 2260);
PAINT MONO (-3140 2260);
DISPLAY INVISIBLE (-3140 2260);
FORCEPROP 1 LAST SIZE 1B
J 0
(-3105 2322);
DISPLAY 0.340426 (-3105 2322);
PAINT GREEN (-3105 2322);
DISPLAY INVISIBLE (-3105 2322);
FORCEPROP 1 LAST PATH I150
J 0
(-3105 2302);
DISPLAY 0.340426 (-3105 2302);
PAINT GREEN (-3105 2302);
DISPLAY INVISIBLE (-3105 2302);
FORCEPROP 2 LAST CDS_LIB mstr_symbols
J 0
(-3150 2300);
PAINT ORANGE (-3150 2300);
DISPLAY INVISIBLE (-3150 2300);
FORCEPROP 1 LAST BODY_TYPE PLUMBING
J 0
(-3195 2257);
DISPLAY 0.340426 (-3195 2257);
PAINT GREEN (-3195 2257);
DISPLAY INVISIBLE (-3195 2257);
FORCEPROP 1 LAST VOLTAGE 3.3V
J 0
(-3195 2257);
DISPLAY 0.340426 (-3195 2257);
PAINT SKYBLUE (-3195 2257);
DISPLAY INVISIBLE (-3195 2257);
FORCEPROP 1 LAST HDL_POWER P3V3_STBY
J 0
(-3450 2175);
DISPLAY 0.872340 (-3450 2175);
PAINT ORANGE (-3450 2175);
DISPLAY INVISIBLE (-3450 2175);
FORCEADD P3V3_STBY..1
(-2750 2250);
FORCEPROP 3 LASTPIN (-2750 2200) SIG_NAME P3V3_STBY\g
J 0
(-2740 2210);
DISPLAY 0.659574 (-2740 2210);
PAINT MONO (-2740 2210);
DISPLAY INVISIBLE (-2740 2210);
FORCEPROP 1 LAST PATH I151
J 0
(-2705 2252);
DISPLAY 0.340426 (-2705 2252);
PAINT GREEN (-2705 2252);
DISPLAY INVISIBLE (-2705 2252);
FORCEPROP 1 LAST BODY_TYPE PLUMBING
J 0
(-2795 2207);
DISPLAY 0.340426 (-2795 2207);
PAINT GREEN (-2795 2207);
DISPLAY INVISIBLE (-2795 2207);
FORCEPROP 2 LAST CDS_LIB mstr_symbols
J 0
(-2750 2250);
PAINT ORANGE (-2750 2250);
DISPLAY INVISIBLE (-2750 2250);
FORCEPROP 1 LAST SIZE 1B
J 0
(-2705 2272);
DISPLAY 0.340426 (-2705 2272);
PAINT GREEN (-2705 2272);
DISPLAY INVISIBLE (-2705 2272);
FORCEPROP 1 LAST VOLTAGE 3.3V
J 0
(-2795 2207);
DISPLAY 0.340426 (-2795 2207);
PAINT SKYBLUE (-2795 2207);
DISPLAY INVISIBLE (-2795 2207);
FORCEPROP 1 LAST HDL_POWER P3V3_STBY
J 0
(-3050 2125);
DISPLAY 0.872340 (-3050 2125);
PAINT ORANGE (-3050 2125);
DISPLAY INVISIBLE (-3050 2125);
FORCEADD OFFPAGE..1
(-4850 2000);
FORCEPROP 2 LASTPIN (-4800 2000) SIG_NAME SMB_LAN_STBY_LVC3_SCL_R2
J 0
(-4800 2010);
DISPLAY 0.617021 (-4800 2010);
PAINT ORANGE (-4800 2010);
FORCEPROP 2 LAST $XR0 120 
J 0
(-5102 2000);
DISPLAY 0.638298 (-5102 2000);
PAINT MONO (-5102 2000);
FORCEPROP 2 LAST PATH I154
J 0
(-5100 2050);
DISPLAY 1.021277 (-5100 2050);
PAINT ORANGE (-5100 2050);
DISPLAY INVISIBLE (-5100 2050);
FORCEPROP 1 LAST OFFPAGE TRUE
J 0
(-4525 1875);
DISPLAY 0.872340 (-4525 1875);
PAINT GREEN (-4525 1875);
DISPLAY INVISIBLE (-4525 1875);
FORCEPROP 2 LAST CDS_LIB mstr_standard
J 0
(-4850 2000);
PAINT ORANGE (-4850 2000);
DISPLAY INVISIBLE (-4850 2000);
FORCEPROP 1 LAST COMMENT_BODY TRUE
J 0
(-4725 1900);
DISPLAY 0.872340 (-4725 1900);
PAINT GREEN (-4725 1900);
DISPLAY INVISIBLE (-4725 1900);
FORCEADD OFFPAGE..6
(-4825 2150);
FORCEPROP 2 LAST $XR0 120 
J 0
(-5105 2150);
DISPLAY 0.638298 (-5105 2150);
PAINT MONO (-5105 2150);
FORCEPROP 2 LAST CDS_LIB mstr_standard
J 0
(-4825 2150);
PAINT ORANGE (-4825 2150);
DISPLAY INVISIBLE (-4825 2150);
FORCEPROP 1 LAST COMMENT_BODY TRUE
J 0
(-4725 2075);
DISPLAY 0.872340 (-4725 2075);
PAINT GREEN (-4725 2075);
DISPLAY INVISIBLE (-4725 2075);
FORCEPROP 2 LAST PATH I155
J 0
(-5125 2200);
DISPLAY 1.021277 (-5125 2200);
PAINT ORANGE (-5125 2200);
DISPLAY INVISIBLE (-5125 2200);
FORCEPROP 1 LAST OFFPAGE TRUE
J 0
(-4500 2025);
DISPLAY 0.872340 (-4500 2025);
PAINT GREEN (-4500 2025);
DISPLAY INVISIBLE (-4500 2025);
FORCEADD OFFPAGE..3
(-2125 1425);
FORCEPROP 2 LAST $XR3 188 
J 0
(-1581 1425);
DISPLAY 0.638298 (-1581 1425);
PAINT MONO (-1581 1425);
FORCEPROP 2 LAST $XR0 91 
J 0
(-1911 1425);
DISPLAY 0.638298 (-1911 1425);
PAINT MONO (-1911 1425);
FORCEPROP 2 LAST $XR1 159 
J 0
(-1821 1425);
DISPLAY 0.638298 (-1821 1425);
PAINT MONO (-1821 1425);
FORCEPROP 2 LAST $XR2 186 
J 0
(-1701 1425);
DISPLAY 0.638298 (-1701 1425);
PAINT MONO (-1701 1425);
FORCEPROP 2 LAST PATH I156
J 0
(-1925 1500);
DISPLAY 1.021277 (-1925 1500);
PAINT ORANGE (-1925 1500);
DISPLAY INVISIBLE (-1925 1500);
FORCEPROP 1 LAST OFFPAGE TRUE
J 0
(-1800 1300);
DISPLAY 0.872340 (-1800 1300);
PAINT GREEN (-1800 1300);
DISPLAY INVISIBLE (-1800 1300);
FORCEPROP 2 LAST CDS_LIB mstr_standard
J 0
(-2125 1425);
PAINT MONO (-2125 1425);
DISPLAY INVISIBLE (-2125 1425);
FORCEPROP 1 LAST COMMENT_BODY TRUE
J 0
(-2175 1325);
DISPLAY 0.872340 (-2175 1325);
PAINT GREEN (-2175 1325);
DISPLAY INVISIBLE (-2175 1325);
FORCEADD OFFPAGE..2
(-2125 1325);
FORCEPROP 2 LAST $XR2 186 
J 0
(-1726 1325);
DISPLAY 0.638298 (-1726 1325);
PAINT MONO (-1726 1325);
FORCEPROP 2 LAST $XR1 91 
J 0
(-1816 1325);
DISPLAY 0.638298 (-1816 1325);
PAINT MONO (-1816 1325);
FORCEPROP 2 LAST $XR0 159 
J 0
(-1936 1325);
DISPLAY 0.638298 (-1936 1325);
PAINT MONO (-1936 1325);
FORCEPROP 2 LAST $XR3 188 
J 0
(-1606 1325);
DISPLAY 0.638298 (-1606 1325);
PAINT MONO (-1606 1325);
FORCEPROP 2 LAST PATH I157
J 0
(-1950 1400);
DISPLAY 1.021277 (-1950 1400);
PAINT ORANGE (-1950 1400);
DISPLAY INVISIBLE (-1950 1400);
FORCEPROP 1 LAST OFFPAGE TRUE
J 0
(-1800 1200);
DISPLAY 0.872340 (-1800 1200);
PAINT GREEN (-1800 1200);
DISPLAY INVISIBLE (-1800 1200);
FORCEPROP 2 LAST CDS_LIB mstr_standard
J 0
(-2125 1325);
PAINT MONO (-2125 1325);
DISPLAY INVISIBLE (-2125 1325);
FORCEPROP 1 LAST COMMENT_BODY TRUE
J 0
(-2170 1230);
DISPLAY 0.872340 (-2170 1230);
PAINT GREEN (-2170 1230);
DISPLAY INVISIBLE (-2170 1230);
FORCEADD RES..1
(-3100 1325);
FORCEPROP 1 LAST PART_NUMBER G21796-173
J 0
(-2850 1275);
DISPLAY 0.617021 (-2850 1275);
PAINT BLUE (-2850 1275);
FORCEPROP 1 LAST MATERIAL EMPTY
J 0
(-2950 1275);
DISPLAY 0.617021 (-2950 1275);
PAINT RED (-2950 1275);
FORCEPROP 1 LASTPIN (-3000 1325) $PN 2
J 0
(-3038 1337);
DISPLAY 0.617021 (-3038 1337);
PAINT ORANGE (-3038 1337);
FORCEPROP 1 LAST TOLERANCE 1%
J 0
(-3025 1275);
DISPLAY 0.617021 (-3025 1275);
PAINT SKYBLUE (-3025 1275);
FORCEPROP 1 LASTPIN (-3200 1325) $PN 1
J 0
(-3188 1337);
DISPLAY 0.617021 (-3188 1337);
PAINT ORANGE (-3188 1337);
FORCEPROP 1 LAST LOCATION R2U8
J 0
(-3300 1325);
DISPLAY 0.617021 (-3300 1325);
PAINT AQUA (-3300 1325);
FORCEPROP 1 LAST VALUE 20.0
J 2
(-3150 1275);
DISPLAY 0.617021 (-3150 1275);
PAINT SKYBLUE (-3150 1275);
FORCEPROP 0 LAST BOM_COST SM_CONTROLLER
J 0
(-2850 1475);
DISPLAY 1.021277 (-2850 1475);
PAINT ORANGE (-2850 1475);
DISPLAY INVISIBLE (-2850 1475);
FORCEPROP 0 LAST SKU A
J 0
(-2850 1375);
DISPLAY 1.021277 (-2850 1375);
PAINT ORANGE (-2850 1375);
DISPLAY INVISIBLE (-2850 1375);
FORCEPROP 0 LAST ROOM SMBUS
J 0
(-2850 1375);
DISPLAY 1.021277 (-2850 1375);
PAINT ORANGE (-2850 1375);
DISPLAY INVISIBLE (-2850 1375);
FORCEPROP 1 LAST PACK_TYPE 0402
J 0
(-2950 1275);
DISPLAY 0.617021 (-2950 1275);
PAINT SKYBLUE (-2950 1275);
DISPLAY INVISIBLE (-2950 1275);
FORCEPROP 2 LAST $SEC 1
J 0
(-3150 1525);
PAINT MONO (-3150 1525);
DISPLAY INVISIBLE (-3150 1525);
FORCEPROP 2 LAST CDS_SEC 1
J 0
(-3150 1525);
PAINT MONO (-3150 1525);
DISPLAY INVISIBLE (-3150 1525);
FORCEPROP 1 LAST PATH I158
J 0
(-3150 1475);
DISPLAY 0.978723 (-3150 1475);
PAINT WHITE (-3150 1475);
DISPLAY INVISIBLE (-3150 1475);
FORCEPROP 2 LAST CDS_LIB mstr_discrete
J 0
(-3100 1325);
PAINT MONO (-3100 1325);
DISPLAY INVISIBLE (-3100 1325);
FORCEPROP 2 LAST CDS_LOCATION R2U8
J 0
(-3300 1325);
DISPLAY 0.617021 (-3300 1325);
PAINT AQUA (-3300 1325);
DISPLAY INVISIBLE (-3300 1325);
FORCEPROP 1 LAST WATTAGE 1/16W
J 2
(-3225 1275);
DISPLAY 0.617021 (-3225 1275);
PAINT SKYBLUE (-3225 1275);
DISPLAY INVISIBLE (-3225 1275);
FORCEADD RES..1
(-3100 1425);
FORCEPROP 1 LAST PART_NUMBER G21796-173
J 0
(-2850 1375);
DISPLAY 0.617021 (-2850 1375);
PAINT BLUE (-2850 1375);
FORCEPROP 1 LAST MATERIAL EMPTY
J 0
(-2950 1375);
DISPLAY 0.617021 (-2950 1375);
PAINT RED (-2950 1375);
FORCEPROP 1 LASTPIN (-3000 1425) $PN 2
J 0
(-3038 1437);
DISPLAY 0.617021 (-3038 1437);
PAINT ORANGE (-3038 1437);
FORCEPROP 1 LAST TOLERANCE 1%
J 0
(-3025 1375);
DISPLAY 0.617021 (-3025 1375);
PAINT SKYBLUE (-3025 1375);
FORCEPROP 1 LAST LOCATION R2U12
J 0
(-3150 1500);
DISPLAY 0.617021 (-3150 1500);
PAINT AQUA (-3150 1500);
FORCEPROP 1 LASTPIN (-3200 1425) $PN 1
J 0
(-3188 1437);
DISPLAY 0.617021 (-3188 1437);
PAINT ORANGE (-3188 1437);
FORCEPROP 1 LAST VALUE 20.0
J 2
(-3150 1375);
DISPLAY 0.617021 (-3150 1375);
PAINT SKYBLUE (-3150 1375);
FORCEPROP 0 LAST BOM_COST SM_CONTROLLER
J 0
(-2850 1575);
DISPLAY 1.021277 (-2850 1575);
PAINT ORANGE (-2850 1575);
DISPLAY INVISIBLE (-2850 1575);
FORCEPROP 0 LAST SKU A
J 0
(-2850 1475);
DISPLAY 1.021277 (-2850 1475);
PAINT ORANGE (-2850 1475);
DISPLAY INVISIBLE (-2850 1475);
FORCEPROP 0 LAST ROOM SMBUS
J 0
(-2850 1475);
DISPLAY 1.021277 (-2850 1475);
PAINT ORANGE (-2850 1475);
DISPLAY INVISIBLE (-2850 1475);
FORCEPROP 1 LAST PACK_TYPE 0402
J 0
(-2950 1375);
DISPLAY 0.617021 (-2950 1375);
PAINT SKYBLUE (-2950 1375);
DISPLAY INVISIBLE (-2950 1375);
FORCEPROP 2 LAST CDS_SEC 1
J 0
(-3150 1625);
PAINT MONO (-3150 1625);
DISPLAY INVISIBLE (-3150 1625);
FORCEPROP 2 LAST $SEC 1
J 0
(-3150 1625);
PAINT MONO (-3150 1625);
DISPLAY INVISIBLE (-3150 1625);
FORCEPROP 1 LAST PATH I159
J 0
(-3150 1575);
DISPLAY 0.978723 (-3150 1575);
PAINT WHITE (-3150 1575);
DISPLAY INVISIBLE (-3150 1575);
FORCEPROP 2 LAST CDS_LIB mstr_discrete
J 0
(-3100 1425);
PAINT MONO (-3100 1425);
DISPLAY INVISIBLE (-3100 1425);
FORCEPROP 2 LAST CDS_LOCATION R2U12
J 0
(-3150 1500);
DISPLAY 0.617021 (-3150 1500);
PAINT AQUA (-3150 1500);
DISPLAY INVISIBLE (-3150 1500);
FORCEPROP 1 LAST WATTAGE 1/16W
J 2
(-3225 1375);
DISPLAY 0.617021 (-3225 1375);
PAINT SKYBLUE (-3225 1375);
DISPLAY INVISIBLE (-3225 1375);
FORCEADD RES..1
(-275 3050);
FORCEPROP 1 LAST VALUE 20.0
J 2
(-450 3075);
DISPLAY 0.617021 (-450 3075);
PAINT SKYBLUE (-450 3075);
FORCEPROP 1 LASTPIN (-175 3050) $PN 2
J 0
(-213 3062);
DISPLAY 0.617021 (-213 3062);
PAINT WHITE (-213 3062);
FORCEPROP 1 LAST LOCATION R8D3
J 0
(-325 3100);
DISPLAY 0.617021 (-325 3100);
PAINT AQUA (-325 3100);
FORCEPROP 1 LAST TOLERANCE 1%
J 0
(-425 3075);
DISPLAY 0.617021 (-425 3075);
PAINT SKYBLUE (-425 3075);
FORCEPROP 1 LASTPIN (-375 3050) $PN 1
J 0
(-363 3062);
DISPLAY 0.617021 (-363 3062);
PAINT WHITE (-363 3062);
FORCEPROP 1 LAST PACK_TYPE 0402
J 0
(200 3075);
DISPLAY 0.617021 (200 3075);
PAINT SKYBLUE (200 3075);
FORCEPROP 1 LAST MATERIAL CHIP
J 0
(75 3075);
DISPLAY 0.617021 (75 3075);
PAINT SKYBLUE (75 3075);
FORCEPROP 1 LAST PART_NUMBER G21796-173
J 0
(-150 3075);
DISPLAY 0.617021 (-150 3075);
PAINT BLUE (-150 3075);
FORCEPROP 1 LAST WATTAGE 1/16W
J 2
(475 3075);
DISPLAY 0.617021 (475 3075);
PAINT SKYBLUE (475 3075);
FORCEPROP 0 LAST BOM_COST SM_CONTROLLER
J 0
(-325 3300);
DISPLAY 1.021277 (-325 3300);
PAINT ORANGE (-325 3300);
DISPLAY INVISIBLE (-325 3300);
FORCEPROP 2 LAST SEC_TYPE 0402
J 0
(-325 3250);
DISPLAY 1.021277 (-325 3250);
PAINT ORANGE (-325 3250);
DISPLAY INVISIBLE (-325 3250);
FORCEPROP 2 LAST SEC 1
J 0
(-325 3250);
DISPLAY 0.680851 (-325 3250);
PAINT MONO (-325 3250);
DISPLAY INVISIBLE (-325 3250);
FORCEPROP 2 LAST CDS_LOCATION R8D3
J 0
(-325 3100);
DISPLAY 0.617021 (-325 3100);
PAINT AQUA (-325 3100);
DISPLAY INVISIBLE (-325 3100);
FORCEPROP 1 LAST PATH I161
J 0
(-325 3200);
DISPLAY 0.978723 (-325 3200);
PAINT WHITE (-325 3200);
DISPLAY INVISIBLE (-325 3200);
FORCEPROP 0 LAST ROOM SMBUS
J 0
(-325 3200);
DISPLAY 1.021277 (-325 3200);
PAINT ORANGE (-325 3200);
DISPLAY INVISIBLE (-325 3200);
FORCEPROP 2 LAST CDS_LIB mstr_discrete
J 0
(-275 3050);
PAINT ORANGE (-275 3050);
DISPLAY INVISIBLE (-275 3050);
FORCEADD RES..1
(-275 3225);
FORCEPROP 1 LAST VALUE 20.0
J 2
(-450 3250);
DISPLAY 0.617021 (-450 3250);
PAINT SKYBLUE (-450 3250);
FORCEPROP 1 LASTPIN (-375 3225) $PN 1
J 0
(-363 3237);
DISPLAY 0.617021 (-363 3237);
PAINT WHITE (-363 3237);
FORCEPROP 1 LASTPIN (-175 3225) $PN 2
J 0
(-213 3237);
DISPLAY 0.617021 (-213 3237);
PAINT WHITE (-213 3237);
FORCEPROP 1 LAST LOCATION R8D6
J 0
(-325 3275);
DISPLAY 0.617021 (-325 3275);
PAINT AQUA (-325 3275);
FORCEPROP 1 LAST PACK_TYPE 0402
J 0
(200 3250);
DISPLAY 0.617021 (200 3250);
PAINT SKYBLUE (200 3250);
FORCEPROP 1 LAST WATTAGE 1/16W
J 2
(475 3250);
DISPLAY 0.617021 (475 3250);
PAINT SKYBLUE (475 3250);
FORCEPROP 1 LAST MATERIAL CHIP
J 0
(75 3250);
DISPLAY 0.617021 (75 3250);
PAINT SKYBLUE (75 3250);
FORCEPROP 1 LAST PART_NUMBER G21796-173
J 0
(-150 3250);
DISPLAY 0.617021 (-150 3250);
PAINT BLUE (-150 3250);
FORCEPROP 1 LAST TOLERANCE 1%
J 0
(-425 3250);
DISPLAY 0.617021 (-425 3250);
PAINT SKYBLUE (-425 3250);
FORCEPROP 2 LAST SEC_TYPE 0402
J 0
(-325 3425);
DISPLAY 1.021277 (-325 3425);
PAINT ORANGE (-325 3425);
DISPLAY INVISIBLE (-325 3425);
FORCEPROP 0 LAST BOM_COST SM_CONTROLLER
J 0
(-325 3475);
DISPLAY 1.021277 (-325 3475);
PAINT ORANGE (-325 3475);
DISPLAY INVISIBLE (-325 3475);
FORCEPROP 0 LAST ROOM SMBUS
J 0
(-325 3375);
DISPLAY 1.021277 (-325 3375);
PAINT ORANGE (-325 3375);
DISPLAY INVISIBLE (-325 3375);
FORCEPROP 1 LAST PATH I162
J 0
(-325 3375);
DISPLAY 0.978723 (-325 3375);
PAINT WHITE (-325 3375);
DISPLAY INVISIBLE (-325 3375);
FORCEPROP 2 LAST SEC 1
J 0
(-325 3425);
DISPLAY 0.680851 (-325 3425);
PAINT MONO (-325 3425);
DISPLAY INVISIBLE (-325 3425);
FORCEPROP 2 LAST CDS_LIB mstr_discrete
J 0
(-275 3225);
PAINT ORANGE (-275 3225);
DISPLAY INVISIBLE (-275 3225);
FORCEPROP 2 LAST CDS_LOCATION R8D6
J 0
(-325 3275);
DISPLAY 0.617021 (-325 3275);
PAINT AQUA (-325 3275);
DISPLAY INVISIBLE (-325 3275);
FORCEADD RES..1
(-275 2275);
FORCEPROP 1 LAST LOCATION R8D7
J 0
(-325 2325);
DISPLAY 0.617021 (-325 2325);
PAINT AQUA (-325 2325);
FORCEPROP 1 LASTPIN (-175 2275) $PN 2
J 0
(-213 2287);
DISPLAY 0.617021 (-213 2287);
PAINT WHITE (-213 2287);
FORCEPROP 1 LAST MATERIAL CHIP
J 0
(75 2300);
DISPLAY 0.617021 (75 2300);
PAINT SKYBLUE (75 2300);
FORCEPROP 1 LAST PART_NUMBER G21796-173
J 0
(-150 2300);
DISPLAY 0.617021 (-150 2300);
PAINT BLUE (-150 2300);
FORCEPROP 1 LAST WATTAGE 1/16W
J 2
(475 2300);
DISPLAY 0.617021 (475 2300);
PAINT SKYBLUE (475 2300);
FORCEPROP 1 LAST PACK_TYPE 0402
J 0
(200 2300);
DISPLAY 0.617021 (200 2300);
PAINT SKYBLUE (200 2300);
FORCEPROP 1 LASTPIN (-375 2275) $PN 1
J 0
(-363 2287);
DISPLAY 0.617021 (-363 2287);
PAINT WHITE (-363 2287);
FORCEPROP 1 LAST TOLERANCE 1%
J 0
(-425 2300);
DISPLAY 0.617021 (-425 2300);
PAINT SKYBLUE (-425 2300);
FORCEPROP 1 LAST VALUE 20.0
J 2
(-450 2300);
DISPLAY 0.617021 (-450 2300);
PAINT SKYBLUE (-450 2300);
FORCEPROP 0 LAST BOM_COST SM_CONTROLLER
J 0
(-325 2525);
DISPLAY 1.021277 (-325 2525);
PAINT ORANGE (-325 2525);
DISPLAY INVISIBLE (-325 2525);
FORCEPROP 1 LAST PATH I163
J 0
(-325 2425);
DISPLAY 0.978723 (-325 2425);
PAINT WHITE (-325 2425);
DISPLAY INVISIBLE (-325 2425);
FORCEPROP 2 LAST CDS_LOCATION R8D7
J 0
(-325 2325);
DISPLAY 0.617021 (-325 2325);
PAINT AQUA (-325 2325);
DISPLAY INVISIBLE (-325 2325);
FORCEPROP 2 LAST SEC 1
J 0
(-325 2475);
DISPLAY 0.680851 (-325 2475);
PAINT MONO (-325 2475);
DISPLAY INVISIBLE (-325 2475);
FORCEPROP 2 LAST SEC_TYPE 0402
J 0
(-325 2475);
DISPLAY 1.021277 (-325 2475);
PAINT ORANGE (-325 2475);
DISPLAY INVISIBLE (-325 2475);
FORCEPROP 0 LAST ROOM SMBUS
J 0
(-325 2425);
DISPLAY 1.021277 (-325 2425);
PAINT ORANGE (-325 2425);
DISPLAY INVISIBLE (-325 2425);
FORCEPROP 2 LAST CDS_LIB mstr_discrete
J 0
(-275 2275);
PAINT ORANGE (-275 2275);
DISPLAY INVISIBLE (-275 2275);
FORCEADD RES..1
(-275 2125);
FORCEPROP 1 LAST PART_NUMBER G21796-173
J 0
(-150 2150);
DISPLAY 0.617021 (-150 2150);
PAINT BLUE (-150 2150);
FORCEPROP 1 LAST MATERIAL CHIP
J 0
(75 2150);
DISPLAY 0.617021 (75 2150);
PAINT SKYBLUE (75 2150);
FORCEPROP 1 LAST PACK_TYPE 0402
J 0
(200 2150);
DISPLAY 0.617021 (200 2150);
PAINT SKYBLUE (200 2150);
FORCEPROP 1 LAST WATTAGE 1/16W
J 2
(475 2150);
DISPLAY 0.617021 (475 2150);
PAINT SKYBLUE (475 2150);
FORCEPROP 1 LAST LOCATION R8D4
J 0
(-325 2175);
DISPLAY 0.617021 (-325 2175);
PAINT AQUA (-325 2175);
FORCEPROP 1 LASTPIN (-175 2125) $PN 2
J 0
(-213 2137);
DISPLAY 0.617021 (-213 2137);
PAINT WHITE (-213 2137);
FORCEPROP 1 LASTPIN (-375 2125) $PN 1
J 0
(-363 2137);
DISPLAY 0.617021 (-363 2137);
PAINT WHITE (-363 2137);
FORCEPROP 1 LAST VALUE 20.0
J 2
(-450 2150);
DISPLAY 0.617021 (-450 2150);
PAINT SKYBLUE (-450 2150);
FORCEPROP 1 LAST TOLERANCE 1%
J 0
(-425 2150);
DISPLAY 0.617021 (-425 2150);
PAINT SKYBLUE (-425 2150);
FORCEPROP 2 LAST SEC 1
J 0
(-325 2325);
DISPLAY 0.680851 (-325 2325);
PAINT MONO (-325 2325);
DISPLAY INVISIBLE (-325 2325);
FORCEPROP 0 LAST BOM_COST SM_CONTROLLER
J 0
(-325 2375);
DISPLAY 1.021277 (-325 2375);
PAINT ORANGE (-325 2375);
DISPLAY INVISIBLE (-325 2375);
FORCEPROP 2 LAST SEC_TYPE 0402
J 0
(-325 2325);
DISPLAY 1.021277 (-325 2325);
PAINT ORANGE (-325 2325);
DISPLAY INVISIBLE (-325 2325);
FORCEPROP 1 LAST PATH I164
J 0
(-325 2275);
DISPLAY 0.978723 (-325 2275);
PAINT WHITE (-325 2275);
DISPLAY INVISIBLE (-325 2275);
FORCEPROP 0 LAST ROOM SMBUS
J 0
(-325 2275);
DISPLAY 1.021277 (-325 2275);
PAINT ORANGE (-325 2275);
DISPLAY INVISIBLE (-325 2275);
FORCEPROP 2 LAST CDS_LOCATION R8D4
J 0
(-325 2175);
DISPLAY 0.617021 (-325 2175);
PAINT AQUA (-325 2175);
DISPLAY INVISIBLE (-325 2175);
FORCEPROP 2 LAST CDS_LIB mstr_discrete
J 0
(-275 2125);
PAINT ORANGE (-275 2125);
DISPLAY INVISIBLE (-275 2125);
FORCEADD RES..1
(-3950 1775);
FORCEPROP 1 LAST PACK_TYPE 0402
J 0
(-3475 1800);
DISPLAY 0.617021 (-3475 1800);
PAINT SKYBLUE (-3475 1800);
FORCEPROP 1 LAST WATTAGE 1/16W
J 2
(-3200 1800);
DISPLAY 0.617021 (-3200 1800);
PAINT SKYBLUE (-3200 1800);
FORCEPROP 1 LAST MATERIAL CHIP
J 0
(-3600 1800);
DISPLAY 0.617021 (-3600 1800);
PAINT SKYBLUE (-3600 1800);
FORCEPROP 1 LAST PART_NUMBER G21796-173
J 0
(-3825 1800);
DISPLAY 0.617021 (-3825 1800);
PAINT BLUE (-3825 1800);
FORCEPROP 1 LAST LOCATION R2U9
J 0
(-4000 1825);
DISPLAY 0.617021 (-4000 1825);
PAINT AQUA (-4000 1825);
FORCEPROP 1 LASTPIN (-4050 1775) $PN 1
J 0
(-4038 1787);
DISPLAY 0.617021 (-4038 1787);
PAINT WHITE (-4038 1787);
FORCEPROP 1 LASTPIN (-3850 1775) $PN 2
J 0
(-3888 1787);
DISPLAY 0.617021 (-3888 1787);
PAINT WHITE (-3888 1787);
FORCEPROP 1 LAST TOLERANCE 1%
J 0
(-4100 1800);
DISPLAY 0.617021 (-4100 1800);
PAINT SKYBLUE (-4100 1800);
FORCEPROP 1 LAST VALUE 20.0
J 2
(-4125 1800);
DISPLAY 0.617021 (-4125 1800);
PAINT SKYBLUE (-4125 1800);
FORCEPROP 0 LAST BOM_COST SM_CONTROLLER
J 0
(-4000 2025);
DISPLAY 1.021277 (-4000 2025);
PAINT ORANGE (-4000 2025);
DISPLAY INVISIBLE (-4000 2025);
FORCEPROP 2 LAST SEC_TYPE 0402
J 0
(-4000 1975);
DISPLAY 1.021277 (-4000 1975);
PAINT ORANGE (-4000 1975);
DISPLAY INVISIBLE (-4000 1975);
FORCEPROP 2 LAST SEC 1
J 0
(-4000 1975);
DISPLAY 0.680851 (-4000 1975);
PAINT MONO (-4000 1975);
DISPLAY INVISIBLE (-4000 1975);
FORCEPROP 1 LAST PATH I165
J 0
(-4000 1925);
DISPLAY 0.978723 (-4000 1925);
PAINT WHITE (-4000 1925);
DISPLAY INVISIBLE (-4000 1925);
FORCEPROP 0 LAST ROOM SMBUS
J 0
(-4000 1925);
DISPLAY 1.021277 (-4000 1925);
PAINT ORANGE (-4000 1925);
DISPLAY INVISIBLE (-4000 1925);
FORCEPROP 2 LAST CDS_LOCATION R2U9
J 0
(-4000 1825);
DISPLAY 0.617021 (-4000 1825);
PAINT AQUA (-4000 1825);
DISPLAY INVISIBLE (-4000 1825);
FORCEPROP 2 LAST CDS_LIB mstr_discrete
J 0
(-3950 1775);
PAINT ORANGE (-3950 1775);
DISPLAY INVISIBLE (-3950 1775);
FORCEADD RES..1
(-3950 1625);
FORCEPROP 1 LAST WATTAGE 1/16W
J 2
(-3200 1650);
DISPLAY 0.617021 (-3200 1650);
PAINT SKYBLUE (-3200 1650);
FORCEPROP 1 LAST PACK_TYPE 0402
J 0
(-3475 1650);
DISPLAY 0.617021 (-3475 1650);
PAINT SKYBLUE (-3475 1650);
FORCEPROP 1 LAST MATERIAL CHIP
J 0
(-3600 1650);
DISPLAY 0.617021 (-3600 1650);
PAINT SKYBLUE (-3600 1650);
FORCEPROP 1 LAST PART_NUMBER G21796-173
J 0
(-3825 1650);
DISPLAY 0.617021 (-3825 1650);
PAINT BLUE (-3825 1650);
FORCEPROP 1 LASTPIN (-3850 1625) $PN 2
J 0
(-3888 1637);
DISPLAY 0.617021 (-3888 1637);
PAINT WHITE (-3888 1637);
FORCEPROP 1 LAST LOCATION R2U6
J 0
(-4000 1675);
DISPLAY 0.617021 (-4000 1675);
PAINT AQUA (-4000 1675);
FORCEPROP 1 LASTPIN (-4050 1625) $PN 1
J 0
(-4038 1637);
DISPLAY 0.617021 (-4038 1637);
PAINT WHITE (-4038 1637);
FORCEPROP 1 LAST TOLERANCE 1%
J 0
(-4100 1650);
DISPLAY 0.617021 (-4100 1650);
PAINT SKYBLUE (-4100 1650);
FORCEPROP 1 LAST VALUE 20.0
J 2
(-4125 1650);
DISPLAY 0.617021 (-4125 1650);
PAINT SKYBLUE (-4125 1650);
FORCEPROP 2 LAST SEC 1
J 0
(-4000 1825);
DISPLAY 0.680851 (-4000 1825);
PAINT MONO (-4000 1825);
DISPLAY INVISIBLE (-4000 1825);
FORCEPROP 0 LAST BOM_COST SM_CONTROLLER
J 0
(-4000 1875);
DISPLAY 1.021277 (-4000 1875);
PAINT ORANGE (-4000 1875);
DISPLAY INVISIBLE (-4000 1875);
FORCEPROP 2 LAST SEC_TYPE 0402
J 0
(-4000 1825);
DISPLAY 1.021277 (-4000 1825);
PAINT ORANGE (-4000 1825);
DISPLAY INVISIBLE (-4000 1825);
FORCEPROP 1 LAST PATH I166
J 0
(-4000 1775);
DISPLAY 0.978723 (-4000 1775);
PAINT WHITE (-4000 1775);
DISPLAY INVISIBLE (-4000 1775);
FORCEPROP 0 LAST ROOM SMBUS
J 0
(-4000 1775);
DISPLAY 1.021277 (-4000 1775);
PAINT ORANGE (-4000 1775);
DISPLAY INVISIBLE (-4000 1775);
FORCEPROP 2 LAST CDS_LIB mstr_discrete
J 0
(-3950 1625);
PAINT ORANGE (-3950 1625);
DISPLAY INVISIBLE (-3950 1625);
FORCEPROP 2 LAST CDS_LOCATION R2U6
J 0
(-4000 1675);
DISPLAY 0.617021 (-4000 1675);
PAINT AQUA (-4000 1675);
DISPLAY INVISIBLE (-4000 1675);
FORCEADD RES..1
(-3975 3700);
FORCEPROP 1 LAST WATTAGE 1/16W
J 2
(-3225 3725);
DISPLAY 0.617021 (-3225 3725);
PAINT SKYBLUE (-3225 3725);
FORCEPROP 1 LAST PACK_TYPE 0402
J 0
(-3500 3725);
DISPLAY 0.617021 (-3500 3725);
PAINT SKYBLUE (-3500 3725);
FORCEPROP 1 LAST MATERIAL CHIP
J 0
(-3625 3725);
DISPLAY 0.617021 (-3625 3725);
PAINT SKYBLUE (-3625 3725);
FORCEPROP 1 LAST PART_NUMBER G21796-173
J 0
(-3850 3725);
DISPLAY 0.617021 (-3850 3725);
PAINT BLUE (-3850 3725);
FORCEPROP 1 LASTPIN (-3875 3700) $PN 2
J 0
(-3913 3712);
DISPLAY 0.617021 (-3913 3712);
PAINT WHITE (-3913 3712);
FORCEPROP 1 LAST LOCATION R8C20
J 0
(-4025 3750);
DISPLAY 0.617021 (-4025 3750);
PAINT AQUA (-4025 3750);
FORCEPROP 1 LASTPIN (-4075 3700) $PN 1
J 0
(-4063 3712);
DISPLAY 0.617021 (-4063 3712);
PAINT WHITE (-4063 3712);
FORCEPROP 1 LAST TOLERANCE 1%
J 0
(-4125 3725);
DISPLAY 0.617021 (-4125 3725);
PAINT SKYBLUE (-4125 3725);
FORCEPROP 1 LAST VALUE 20.0
J 2
(-4150 3725);
DISPLAY 0.617021 (-4150 3725);
PAINT SKYBLUE (-4150 3725);
FORCEPROP 1 LAST PATH I167
J 0
(-4025 3850);
DISPLAY 0.978723 (-4025 3850);
PAINT WHITE (-4025 3850);
DISPLAY INVISIBLE (-4025 3850);
FORCEPROP 2 LAST SEC 1
J 0
(-4025 3900);
DISPLAY 0.680851 (-4025 3900);
PAINT MONO (-4025 3900);
DISPLAY INVISIBLE (-4025 3900);
FORCEPROP 2 LAST SEC_TYPE 0402
J 0
(-4025 3900);
DISPLAY 1.021277 (-4025 3900);
PAINT ORANGE (-4025 3900);
DISPLAY INVISIBLE (-4025 3900);
FORCEPROP 0 LAST BOM_COST SM_CONTROLLER
J 0
(-4025 3950);
DISPLAY 1.021277 (-4025 3950);
PAINT ORANGE (-4025 3950);
DISPLAY INVISIBLE (-4025 3950);
FORCEPROP 0 LAST ROOM SMBUS
J 0
(-4025 3850);
DISPLAY 1.021277 (-4025 3850);
PAINT ORANGE (-4025 3850);
DISPLAY INVISIBLE (-4025 3850);
FORCEPROP 2 LAST CDS_LOCATION R8C20
J 0
(-4025 3750);
DISPLAY 0.617021 (-4025 3750);
PAINT AQUA (-4025 3750);
DISPLAY INVISIBLE (-4025 3750);
FORCEPROP 2 LAST CDS_LIB mstr_discrete
J 0
(-3975 3700);
PAINT ORANGE (-3975 3700);
DISPLAY INVISIBLE (-3975 3700);
FORCEADD RES..1
(-3975 3550);
FORCEPROP 1 LAST WATTAGE 1/16W
J 2
(-3225 3575);
DISPLAY 0.617021 (-3225 3575);
PAINT SKYBLUE (-3225 3575);
FORCEPROP 1 LAST PACK_TYPE 0402
J 0
(-3500 3575);
DISPLAY 0.617021 (-3500 3575);
PAINT SKYBLUE (-3500 3575);
FORCEPROP 1 LAST MATERIAL CHIP
J 0
(-3625 3575);
DISPLAY 0.617021 (-3625 3575);
PAINT SKYBLUE (-3625 3575);
FORCEPROP 1 LAST PART_NUMBER G21796-173
J 0
(-3850 3575);
DISPLAY 0.617021 (-3850 3575);
PAINT BLUE (-3850 3575);
FORCEPROP 1 LAST LOCATION R8C14
J 0
(-4025 3600);
DISPLAY 0.617021 (-4025 3600);
PAINT AQUA (-4025 3600);
FORCEPROP 1 LASTPIN (-4075 3550) $PN 1
J 0
(-4063 3562);
DISPLAY 0.617021 (-4063 3562);
PAINT WHITE (-4063 3562);
FORCEPROP 1 LASTPIN (-3875 3550) $PN 2
J 0
(-3913 3562);
DISPLAY 0.617021 (-3913 3562);
PAINT WHITE (-3913 3562);
FORCEPROP 1 LAST TOLERANCE 1%
J 0
(-4125 3575);
DISPLAY 0.617021 (-4125 3575);
PAINT SKYBLUE (-4125 3575);
FORCEPROP 1 LAST VALUE 20.0
J 2
(-4150 3575);
DISPLAY 0.617021 (-4150 3575);
PAINT SKYBLUE (-4150 3575);
FORCEPROP 0 LAST BOM_COST SM_CONTROLLER
J 0
(-4025 3800);
DISPLAY 1.021277 (-4025 3800);
PAINT ORANGE (-4025 3800);
DISPLAY INVISIBLE (-4025 3800);
FORCEPROP 0 LAST ROOM SMBUS
J 0
(-4025 3700);
DISPLAY 1.021277 (-4025 3700);
PAINT ORANGE (-4025 3700);
DISPLAY INVISIBLE (-4025 3700);
FORCEPROP 2 LAST SEC_TYPE 0402
J 0
(-4025 3750);
DISPLAY 1.021277 (-4025 3750);
PAINT ORANGE (-4025 3750);
DISPLAY INVISIBLE (-4025 3750);
FORCEPROP 2 LAST SEC 1
J 0
(-4025 3750);
DISPLAY 0.680851 (-4025 3750);
PAINT MONO (-4025 3750);
DISPLAY INVISIBLE (-4025 3750);
FORCEPROP 2 LAST CDS_LOCATION R8C14
J 0
(-4025 3600);
DISPLAY 0.617021 (-4025 3600);
PAINT AQUA (-4025 3600);
DISPLAY INVISIBLE (-4025 3600);
FORCEPROP 1 LAST PATH I168
J 0
(-4025 3700);
DISPLAY 0.978723 (-4025 3700);
PAINT WHITE (-4025 3700);
DISPLAY INVISIBLE (-4025 3700);
FORCEPROP 2 LAST CDS_LIB mstr_discrete
J 0
(-3975 3550);
PAINT ORANGE (-3975 3550);
DISPLAY INVISIBLE (-3975 3550);
FORCEADD RES..1
(-3975 4625);
FORCEPROP 1 LAST WATTAGE 1/16W
J 2
(-3225 4650);
DISPLAY 0.617021 (-3225 4650);
PAINT SKYBLUE (-3225 4650);
FORCEPROP 1 LAST PACK_TYPE 0402
J 0
(-3500 4650);
DISPLAY 0.617021 (-3500 4650);
PAINT SKYBLUE (-3500 4650);
FORCEPROP 1 LAST MATERIAL CHIP
J 0
(-3625 4650);
DISPLAY 0.617021 (-3625 4650);
PAINT SKYBLUE (-3625 4650);
FORCEPROP 1 LAST PART_NUMBER G21796-173
J 0
(-3850 4650);
DISPLAY 0.617021 (-3850 4650);
PAINT BLUE (-3850 4650);
FORCEPROP 1 LASTPIN (-3875 4625) $PN 2
J 0
(-3913 4637);
DISPLAY 0.617021 (-3913 4637);
PAINT WHITE (-3913 4637);
FORCEPROP 1 LAST LOCATION R8C11
J 0
(-4025 4675);
DISPLAY 0.617021 (-4025 4675);
PAINT AQUA (-4025 4675);
FORCEPROP 1 LASTPIN (-4075 4625) $PN 1
J 0
(-4063 4637);
DISPLAY 0.617021 (-4063 4637);
PAINT WHITE (-4063 4637);
FORCEPROP 1 LAST TOLERANCE 1%
J 0
(-4125 4650);
DISPLAY 0.617021 (-4125 4650);
PAINT SKYBLUE (-4125 4650);
FORCEPROP 1 LAST VALUE 20.0
J 2
(-4150 4650);
DISPLAY 0.617021 (-4150 4650);
PAINT SKYBLUE (-4150 4650);
FORCEPROP 0 LAST BOM_COST SM_CONTROLLER
J 0
(-4025 4875);
DISPLAY 1.021277 (-4025 4875);
PAINT ORANGE (-4025 4875);
DISPLAY INVISIBLE (-4025 4875);
FORCEPROP 2 LAST SEC_TYPE 0402
J 0
(-4025 4825);
DISPLAY 1.021277 (-4025 4825);
PAINT ORANGE (-4025 4825);
DISPLAY INVISIBLE (-4025 4825);
FORCEPROP 2 LAST SEC 1
J 0
(-4025 4825);
DISPLAY 0.680851 (-4025 4825);
PAINT MONO (-4025 4825);
DISPLAY INVISIBLE (-4025 4825);
FORCEPROP 1 LAST PATH I169
J 0
(-4025 4775);
DISPLAY 0.978723 (-4025 4775);
PAINT WHITE (-4025 4775);
DISPLAY INVISIBLE (-4025 4775);
FORCEPROP 0 LAST ROOM SMBUS
J 0
(-4025 4775);
DISPLAY 1.021277 (-4025 4775);
PAINT ORANGE (-4025 4775);
DISPLAY INVISIBLE (-4025 4775);
FORCEPROP 2 LAST CDS_LIB mstr_discrete
J 0
(-3975 4625);
PAINT ORANGE (-3975 4625);
DISPLAY INVISIBLE (-3975 4625);
FORCEPROP 2 LAST CDS_LOCATION R8C11
J 0
(-4025 4675);
DISPLAY 0.617021 (-4025 4675);
PAINT AQUA (-4025 4675);
DISPLAY INVISIBLE (-4025 4675);
FORCEADD RES..1
(-3975 4475);
FORCEPROP 1 LAST TOLERANCE 1%
J 0
(-4125 4500);
DISPLAY 0.617021 (-4125 4500);
PAINT SKYBLUE (-4125 4500);
FORCEPROP 1 LAST LOCATION R8C12
J 0
(-4025 4525);
DISPLAY 0.617021 (-4025 4525);
PAINT AQUA (-4025 4525);
FORCEPROP 1 LAST WATTAGE 1/16W
J 2
(-3225 4500);
DISPLAY 0.617021 (-3225 4500);
PAINT SKYBLUE (-3225 4500);
FORCEPROP 1 LAST PACK_TYPE 0402
J 0
(-3500 4500);
DISPLAY 0.617021 (-3500 4500);
PAINT SKYBLUE (-3500 4500);
FORCEPROP 1 LAST MATERIAL CHIP
J 0
(-3625 4500);
DISPLAY 0.617021 (-3625 4500);
PAINT SKYBLUE (-3625 4500);
FORCEPROP 1 LAST PART_NUMBER G21796-173
J 0
(-3850 4500);
DISPLAY 0.617021 (-3850 4500);
PAINT BLUE (-3850 4500);
FORCEPROP 1 LASTPIN (-3875 4475) $PN 2
J 0
(-3913 4487);
DISPLAY 0.617021 (-3913 4487);
PAINT WHITE (-3913 4487);
FORCEPROP 1 LASTPIN (-4075 4475) $PN 1
J 0
(-4063 4487);
DISPLAY 0.617021 (-4063 4487);
PAINT WHITE (-4063 4487);
FORCEPROP 1 LAST VALUE 20.0
J 2
(-4150 4500);
DISPLAY 0.617021 (-4150 4500);
PAINT SKYBLUE (-4150 4500);
FORCEPROP 0 LAST BOM_COST SM_CONTROLLER
J 0
(-4025 4725);
DISPLAY 1.021277 (-4025 4725);
PAINT ORANGE (-4025 4725);
DISPLAY INVISIBLE (-4025 4725);
FORCEPROP 1 LAST PATH I170
J 0
(-4025 4625);
DISPLAY 0.978723 (-4025 4625);
PAINT WHITE (-4025 4625);
DISPLAY INVISIBLE (-4025 4625);
FORCEPROP 2 LAST SEC 1
J 0
(-4025 4675);
DISPLAY 0.680851 (-4025 4675);
PAINT MONO (-4025 4675);
DISPLAY INVISIBLE (-4025 4675);
FORCEPROP 2 LAST SEC_TYPE 0402
J 0
(-4025 4675);
DISPLAY 1.021277 (-4025 4675);
PAINT ORANGE (-4025 4675);
DISPLAY INVISIBLE (-4025 4675);
FORCEPROP 0 LAST ROOM SMBUS
J 0
(-4025 4625);
DISPLAY 1.021277 (-4025 4625);
PAINT ORANGE (-4025 4625);
DISPLAY INVISIBLE (-4025 4625);
FORCEPROP 2 LAST CDS_LIB mstr_discrete
J 0
(-3975 4475);
PAINT ORANGE (-3975 4475);
DISPLAY INVISIBLE (-3975 4475);
FORCEPROP 2 LAST CDS_LOCATION R8C12
J 0
(-4025 4525);
DISPLAY 0.617021 (-4025 4525);
PAINT AQUA (-4025 4525);
DISPLAY INVISIBLE (-4025 4525);
FORCEADD RES..1
(-3975 2150);
FORCEPROP 1 LAST WATTAGE 1/16W
J 2
(-3225 2175);
DISPLAY 0.617021 (-3225 2175);
PAINT SKYBLUE (-3225 2175);
FORCEPROP 1 LAST PACK_TYPE 0402
J 0
(-3500 2175);
DISPLAY 0.617021 (-3500 2175);
PAINT SKYBLUE (-3500 2175);
FORCEPROP 1 LAST MATERIAL CHIP
J 0
(-3625 2175);
DISPLAY 0.617021 (-3625 2175);
PAINT SKYBLUE (-3625 2175);
FORCEPROP 1 LAST PART_NUMBER G21497-005
J 0
(-3850 2175);
DISPLAY 0.617021 (-3850 2175);
PAINT BLUE (-3850 2175);
FORCEPROP 1 LASTPIN (-3875 2150) $PN 2
J 0
(-3913 2162);
DISPLAY 0.617021 (-3913 2162);
PAINT WHITE (-3913 2162);
FORCEPROP 1 LAST LOCATION R2N20
J 0
(-4025 2200);
DISPLAY 0.617021 (-4025 2200);
PAINT AQUA (-4025 2200);
FORCEPROP 1 LASTPIN (-4075 2150) $PN 1
J 0
(-4063 2162);
DISPLAY 0.617021 (-4063 2162);
PAINT WHITE (-4063 2162);
FORCEPROP 1 LAST TOLERANCE 5%
J 0
(-4125 2175);
DISPLAY 0.617021 (-4125 2175);
PAINT SKYBLUE (-4125 2175);
FORCEPROP 1 LAST VALUE 0.0
J 2
(-4150 2175);
DISPLAY 0.617021 (-4150 2175);
PAINT SKYBLUE (-4150 2175);
FORCEPROP 2 LAST SEC 1
J 0
(-4025 2350);
DISPLAY 0.680851 (-4025 2350);
PAINT MONO (-4025 2350);
DISPLAY INVISIBLE (-4025 2350);
FORCEPROP 0 LAST BOM_COST SM_CONTROLLER
J 0
(-4025 2400);
DISPLAY 1.021277 (-4025 2400);
PAINT ORANGE (-4025 2400);
DISPLAY INVISIBLE (-4025 2400);
FORCEPROP 2 LAST SEC_TYPE 0402
J 0
(-4025 2350);
DISPLAY 1.021277 (-4025 2350);
PAINT ORANGE (-4025 2350);
DISPLAY INVISIBLE (-4025 2350);
FORCEPROP 1 LAST PATH I171
J 0
(-4025 2300);
DISPLAY 0.978723 (-4025 2300);
PAINT WHITE (-4025 2300);
DISPLAY INVISIBLE (-4025 2300);
FORCEPROP 0 LAST ROOM SMBUS
J 0
(-4025 2300);
DISPLAY 1.021277 (-4025 2300);
PAINT ORANGE (-4025 2300);
DISPLAY INVISIBLE (-4025 2300);
FORCEPROP 2 LAST CDS_LOCATION R2N20
J 0
(-4025 2200);
DISPLAY 0.617021 (-4025 2200);
PAINT AQUA (-4025 2200);
DISPLAY INVISIBLE (-4025 2200);
FORCEPROP 2 LAST CDS_LIB mstr_discrete
J 0
(-3975 2150);
PAINT ORANGE (-3975 2150);
DISPLAY INVISIBLE (-3975 2150);
FORCEADD RES..1
(-3950 2650);
FORCEPROP 1 LAST WATTAGE 1/16W
J 2
(-3200 2675);
DISPLAY 0.617021 (-3200 2675);
PAINT SKYBLUE (-3200 2675);
FORCEPROP 1 LAST PACK_TYPE 0402
J 0
(-3475 2675);
DISPLAY 0.617021 (-3475 2675);
PAINT SKYBLUE (-3475 2675);
FORCEPROP 1 LAST MATERIAL CHIP
J 0
(-3600 2675);
DISPLAY 0.617021 (-3600 2675);
PAINT SKYBLUE (-3600 2675);
FORCEPROP 1 LAST PART_NUMBER G21796-173
J 0
(-3825 2675);
DISPLAY 0.617021 (-3825 2675);
PAINT BLUE (-3825 2675);
FORCEPROP 1 LASTPIN (-3850 2650) $PN 2
J 0
(-3888 2662);
DISPLAY 0.617021 (-3888 2662);
PAINT WHITE (-3888 2662);
FORCEPROP 1 LAST LOCATION R8B27
J 0
(-4000 2700);
DISPLAY 0.617021 (-4000 2700);
PAINT AQUA (-4000 2700);
FORCEPROP 1 LASTPIN (-4050 2650) $PN 1
J 0
(-4038 2662);
DISPLAY 0.617021 (-4038 2662);
PAINT WHITE (-4038 2662);
FORCEPROP 1 LAST TOLERANCE 1%
J 0
(-4100 2675);
DISPLAY 0.617021 (-4100 2675);
PAINT SKYBLUE (-4100 2675);
FORCEPROP 1 LAST VALUE 20.0
J 2
(-4125 2675);
DISPLAY 0.617021 (-4125 2675);
PAINT SKYBLUE (-4125 2675);
FORCEPROP 2 LAST SEC 1
J 0
(-4000 2850);
DISPLAY 0.680851 (-4000 2850);
PAINT MONO (-4000 2850);
DISPLAY INVISIBLE (-4000 2850);
FORCEPROP 2 LAST SEC_TYPE 0402
J 0
(-4000 2850);
DISPLAY 1.021277 (-4000 2850);
PAINT ORANGE (-4000 2850);
DISPLAY INVISIBLE (-4000 2850);
FORCEPROP 0 LAST BOM_COST SM_CONTROLLER
J 0
(-4000 2900);
DISPLAY 1.021277 (-4000 2900);
PAINT ORANGE (-4000 2900);
DISPLAY INVISIBLE (-4000 2900);
FORCEPROP 1 LAST PATH I173
J 0
(-4000 2800);
DISPLAY 0.978723 (-4000 2800);
PAINT WHITE (-4000 2800);
DISPLAY INVISIBLE (-4000 2800);
FORCEPROP 0 LAST ROOM SMBUS
J 0
(-4000 2800);
DISPLAY 1.021277 (-4000 2800);
PAINT ORANGE (-4000 2800);
DISPLAY INVISIBLE (-4000 2800);
FORCEPROP 2 LAST CDS_LIB mstr_discrete
J 0
(-3950 2650);
PAINT ORANGE (-3950 2650);
DISPLAY INVISIBLE (-3950 2650);
FORCEPROP 2 LAST CDS_LOCATION R8B27
J 0
(-4000 2700);
DISPLAY 0.617021 (-4000 2700);
PAINT AQUA (-4000 2700);
DISPLAY INVISIBLE (-4000 2700);
FORCEADD RES..1
(-3950 2500);
FORCEPROP 1 LAST WATTAGE 1/16W
J 2
(-3200 2525);
DISPLAY 0.617021 (-3200 2525);
PAINT SKYBLUE (-3200 2525);
FORCEPROP 1 LAST PACK_TYPE 0402
J 0
(-3475 2525);
DISPLAY 0.617021 (-3475 2525);
PAINT SKYBLUE (-3475 2525);
FORCEPROP 1 LAST MATERIAL CHIP
J 0
(-3600 2525);
DISPLAY 0.617021 (-3600 2525);
PAINT SKYBLUE (-3600 2525);
FORCEPROP 1 LAST PART_NUMBER G21796-173
J 0
(-3825 2525);
DISPLAY 0.617021 (-3825 2525);
PAINT BLUE (-3825 2525);
FORCEPROP 1 LAST LOCATION R8B28
J 0
(-4000 2550);
DISPLAY 0.617021 (-4000 2550);
PAINT AQUA (-4000 2550);
FORCEPROP 1 LASTPIN (-3850 2500) $PN 2
J 0
(-3888 2512);
DISPLAY 0.617021 (-3888 2512);
PAINT WHITE (-3888 2512);
FORCEPROP 1 LASTPIN (-4050 2500) $PN 1
J 0
(-4038 2512);
DISPLAY 0.617021 (-4038 2512);
PAINT WHITE (-4038 2512);
FORCEPROP 1 LAST TOLERANCE 1%
J 0
(-4100 2525);
DISPLAY 0.617021 (-4100 2525);
PAINT SKYBLUE (-4100 2525);
FORCEPROP 1 LAST VALUE 20.0
J 2
(-4125 2525);
DISPLAY 0.617021 (-4125 2525);
PAINT SKYBLUE (-4125 2525);
FORCEPROP 0 LAST BOM_COST SM_CONTROLLER
J 0
(-4000 2750);
DISPLAY 1.021277 (-4000 2750);
PAINT ORANGE (-4000 2750);
DISPLAY INVISIBLE (-4000 2750);
FORCEPROP 2 LAST SEC_TYPE 0402
J 0
(-4000 2700);
DISPLAY 1.021277 (-4000 2700);
PAINT ORANGE (-4000 2700);
DISPLAY INVISIBLE (-4000 2700);
FORCEPROP 2 LAST SEC 1
J 0
(-4000 2700);
DISPLAY 0.680851 (-4000 2700);
PAINT MONO (-4000 2700);
DISPLAY INVISIBLE (-4000 2700);
FORCEPROP 1 LAST PATH I174
J 0
(-4000 2650);
DISPLAY 0.978723 (-4000 2650);
PAINT WHITE (-4000 2650);
DISPLAY INVISIBLE (-4000 2650);
FORCEPROP 0 LAST ROOM SMBUS
J 0
(-4000 2650);
DISPLAY 1.021277 (-4000 2650);
PAINT ORANGE (-4000 2650);
DISPLAY INVISIBLE (-4000 2650);
FORCEPROP 2 LAST CDS_LOCATION R8B28
J 0
(-4000 2550);
DISPLAY 0.617021 (-4000 2550);
PAINT AQUA (-4000 2550);
DISPLAY INVISIBLE (-4000 2550);
FORCEPROP 2 LAST CDS_LIB mstr_discrete
J 0
(-3950 2500);
PAINT ORANGE (-3950 2500);
DISPLAY INVISIBLE (-3950 2500);
FORCEADD RES..1
(-3975 2000);
FORCEPROP 1 LAST WATTAGE 1/16W
J 2
(-3225 2025);
DISPLAY 0.617021 (-3225 2025);
PAINT SKYBLUE (-3225 2025);
FORCEPROP 1 LAST PACK_TYPE 0402
J 0
(-3500 2025);
DISPLAY 0.617021 (-3500 2025);
PAINT SKYBLUE (-3500 2025);
FORCEPROP 1 LAST PART_NUMBER G21497-005
J 0
(-3850 2025);
DISPLAY 0.617021 (-3850 2025);
PAINT BLUE (-3850 2025);
FORCEPROP 1 LASTPIN (-3875 2000) $PN 2
J 0
(-3913 2012);
DISPLAY 0.617021 (-3913 2012);
PAINT WHITE (-3913 2012);
FORCEPROP 1 LASTPIN (-4075 2000) $PN 1
J 0
(-4063 2012);
DISPLAY 0.617021 (-4063 2012);
PAINT WHITE (-4063 2012);
FORCEPROP 1 LAST TOLERANCE 5%
J 0
(-4125 2025);
DISPLAY 0.617021 (-4125 2025);
PAINT SKYBLUE (-4125 2025);
FORCEPROP 1 LAST MATERIAL CHIP
J 0
(-3625 2025);
DISPLAY 0.617021 (-3625 2025);
PAINT SKYBLUE (-3625 2025);
FORCEPROP 1 LAST LOCATION R2N21
J 0
(-4025 2050);
DISPLAY 0.617021 (-4025 2050);
PAINT AQUA (-4025 2050);
FORCEPROP 1 LAST VALUE 0.0
J 2
(-4150 2025);
DISPLAY 0.617021 (-4150 2025);
PAINT SKYBLUE (-4150 2025);
FORCEPROP 2 LAST SEC 1
J 0
(-4025 2200);
DISPLAY 0.680851 (-4025 2200);
PAINT MONO (-4025 2200);
DISPLAY INVISIBLE (-4025 2200);
FORCEPROP 0 LAST BOM_COST SM_CONTROLLER
J 0
(-4025 2250);
DISPLAY 1.021277 (-4025 2250);
PAINT ORANGE (-4025 2250);
DISPLAY INVISIBLE (-4025 2250);
FORCEPROP 2 LAST SEC_TYPE 0402
J 0
(-4025 2200);
DISPLAY 1.021277 (-4025 2200);
PAINT ORANGE (-4025 2200);
DISPLAY INVISIBLE (-4025 2200);
FORCEPROP 1 LAST PATH I175
J 0
(-4025 2150);
DISPLAY 0.978723 (-4025 2150);
PAINT WHITE (-4025 2150);
DISPLAY INVISIBLE (-4025 2150);
FORCEPROP 0 LAST ROOM SMBUS
J 0
(-4025 2150);
DISPLAY 1.021277 (-4025 2150);
PAINT ORANGE (-4025 2150);
DISPLAY INVISIBLE (-4025 2150);
FORCEPROP 2 LAST CDS_LOCATION R2N21
J 0
(-4025 2050);
DISPLAY 0.617021 (-4025 2050);
PAINT AQUA (-4025 2050);
DISPLAY INVISIBLE (-4025 2050);
FORCEPROP 2 LAST CDS_LIB mstr_discrete
J 0
(-3975 2000);
PAINT ORANGE (-3975 2000);
DISPLAY INVISIBLE (-3975 2000);
FORCEADD OFFPAGE..3
(1550 4150);
FORCEPROP 2 LAST $XR3 247 
J 0
(2004 4150);
DISPLAY 0.638298 (2004 4150);
PAINT MONO (2004 4150);
FORCEPROP 2 LAST $XR2 199 
J 0
(2004 4150);
DISPLAY 0.638298 (2004 4150);
PAINT MONO (2004 4150);
FORCEPROP 2 LAST $XR1 181 
J 0
(1884 4150);
DISPLAY 0.638298 (1884 4150);
PAINT MONO (1884 4150);
FORCEPROP 2 LAST $XR0 159 
J 0
(1764 4150);
DISPLAY 0.638298 (1764 4150);
PAINT MONO (1764 4150);
FORCEPROP 2 LAST PATH I45
J 0
(1775 4200);
DISPLAY 1.021277 (1775 4200);
PAINT ORANGE (1775 4200);
DISPLAY INVISIBLE (1775 4200);
FORCEPROP 2 LAST CDS_LIB mstr_standard
J 0
(1550 4150);
PAINT ORANGE (1550 4150);
DISPLAY INVISIBLE (1550 4150);
FORCEPROP 1 LAST OFFPAGE TRUE
J 0
(1875 4025);
DISPLAY 0.872340 (1875 4025);
PAINT GREEN (1875 4025);
DISPLAY INVISIBLE (1875 4025);
FORCEPROP 1 LAST COMMENT_BODY TRUE
J 0
(1500 4050);
DISPLAY 0.872340 (1500 4050);
PAINT GREEN (1500 4050);
DISPLAY INVISIBLE (1500 4050);
FORCEADD OFFPAGE..2
(1550 4000);
FORCEPROP 2 LAST $XR3 199 
J 0
(1979 4000);
DISPLAY 0.638298 (1979 4000);
PAINT MONO (1979 4000);
FORCEPROP 2 LAST $XR2 247 
J 0
(1979 4000);
DISPLAY 0.638298 (1979 4000);
PAINT MONO (1979 4000);
FORCEPROP 2 LAST $XR1 181 
J 0
(1859 4000);
DISPLAY 0.638298 (1859 4000);
PAINT MONO (1859 4000);
FORCEPROP 2 LAST $XR0 159 
J 0
(1739 4000);
DISPLAY 0.638298 (1739 4000);
PAINT MONO (1739 4000);
FORCEPROP 2 LAST PATH I46
J 0
(1775 4050);
DISPLAY 1.021277 (1775 4050);
PAINT ORANGE (1775 4050);
DISPLAY INVISIBLE (1775 4050);
FORCEPROP 1 LAST OFFPAGE TRUE
J 0
(1875 3875);
DISPLAY 0.872340 (1875 3875);
PAINT GREEN (1875 3875);
DISPLAY INVISIBLE (1875 3875);
FORCEPROP 2 LAST CDS_LIB mstr_standard
J 0
(1550 4000);
PAINT ORANGE (1550 4000);
DISPLAY INVISIBLE (1550 4000);
FORCEPROP 1 LAST COMMENT_BODY TRUE
J 0
(1505 3905);
DISPLAY 0.872340 (1505 3905);
PAINT GREEN (1505 3905);
DISPLAY INVISIBLE (1505 3905);
FORCEADD OFFPAGE..2
(1550 3050);
FORCEPROP 2 LAST $XR1 167 
J 0
(1859 3050);
DISPLAY 0.638298 (1859 3050);
PAINT MONO (1859 3050);
FORCEPROP 2 LAST $XR0 165 
J 0
(1739 3050);
DISPLAY 0.638298 (1739 3050);
PAINT MONO (1739 3050);
FORCEPROP 2 LAST PATH I47
J 0
(1775 3100);
DISPLAY 1.021277 (1775 3100);
PAINT ORANGE (1775 3100);
DISPLAY INVISIBLE (1775 3100);
FORCEPROP 2 LAST CDS_LIB mstr_standard
J 0
(1550 3050);
PAINT ORANGE (1550 3050);
DISPLAY INVISIBLE (1550 3050);
FORCEPROP 1 LAST OFFPAGE TRUE
J 0
(1875 2925);
DISPLAY 0.872340 (1875 2925);
PAINT GREEN (1875 2925);
DISPLAY INVISIBLE (1875 2925);
FORCEPROP 1 LAST COMMENT_BODY TRUE
J 0
(1505 2955);
DISPLAY 0.872340 (1505 2955);
PAINT GREEN (1505 2955);
DISPLAY INVISIBLE (1505 2955);
FORCEADD OFFPAGE..3
(1550 3225);
FORCEPROP 2 LAST $XR1 167 
J 0
(1884 3225);
DISPLAY 0.638298 (1884 3225);
PAINT MONO (1884 3225);
FORCEPROP 2 LAST $XR0 165 
J 0
(1764 3225);
DISPLAY 0.638298 (1764 3225);
PAINT MONO (1764 3225);
FORCEPROP 1 LAST OFFPAGE TRUE
J 0
(1875 3100);
DISPLAY 0.872340 (1875 3100);
PAINT GREEN (1875 3100);
DISPLAY INVISIBLE (1875 3100);
FORCEPROP 2 LAST PATH I48
J 0
(1775 3275);
DISPLAY 1.021277 (1775 3275);
PAINT ORANGE (1775 3275);
DISPLAY INVISIBLE (1775 3275);
FORCEPROP 2 LAST CDS_LIB mstr_standard
J 0
(1550 3225);
PAINT ORANGE (1550 3225);
DISPLAY INVISIBLE (1550 3225);
FORCEPROP 1 LAST COMMENT_BODY TRUE
J 0
(1500 3125);
DISPLAY 0.872340 (1500 3125);
PAINT GREEN (1500 3125);
DISPLAY INVISIBLE (1500 3125);
FORCEADD OFFPAGE..3
(1550 2275);
FORCEPROP 2 LAST $XR11 235 
J 0
(2244 2239);
DISPLAY 0.638298 (2244 2239);
PAINT MONO (2244 2239);
FORCEPROP 2 LAST $XR10 226 
J 0
(2124 2239);
DISPLAY 0.638298 (2124 2239);
PAINT MONO (2124 2239);
FORCEPROP 2 LAST $XR9 223 
J 0
(2004 2239);
DISPLAY 0.638298 (2004 2239);
PAINT MONO (2004 2239);
FORCEPROP 2 LAST $XR8 218 
J 0
(1884 2239);
DISPLAY 0.638298 (1884 2239);
PAINT MONO (1884 2239);
FORCEPROP 2 LAST $XR7 215 
J 0
(1764 2239);
DISPLAY 0.638298 (1764 2239);
PAINT MONO (1764 2239);
FORCEPROP 2 LAST $XR6 213 
J 0
(2484 2275);
DISPLAY 0.638298 (2484 2275);
PAINT MONO (2484 2275);
FORCEPROP 2 LAST $XR5 211 
J 0
(2364 2275);
DISPLAY 0.638298 (2364 2275);
PAINT MONO (2364 2275);
FORCEPROP 2 LAST $XR4 206 
J 0
(2244 2275);
DISPLAY 0.638298 (2244 2275);
PAINT MONO (2244 2275);
FORCEPROP 2 LAST $XR3 201 
J 0
(2124 2275);
DISPLAY 0.638298 (2124 2275);
PAINT MONO (2124 2275);
FORCEPROP 2 LAST $XR2 194 
J 0
(2004 2275);
DISPLAY 0.638298 (2004 2275);
PAINT MONO (2004 2275);
FORCEPROP 2 LAST $XR1 193 
J 0
(1884 2275);
DISPLAY 0.638298 (1884 2275);
PAINT MONO (1884 2275);
FORCEPROP 2 LAST $XR0 159 
J 0
(1764 2275);
DISPLAY 0.638298 (1764 2275);
PAINT MONO (1764 2275);
FORCEPROP 1 LAST OFFPAGE TRUE
J 0
(1875 2150);
DISPLAY 0.872340 (1875 2150);
PAINT GREEN (1875 2150);
DISPLAY INVISIBLE (1875 2150);
FORCEPROP 2 LAST PATH I49
J 0
(1775 2325);
DISPLAY 1.021277 (1775 2325);
PAINT ORANGE (1775 2325);
DISPLAY INVISIBLE (1775 2325);
FORCEPROP 2 LAST CDS_LIB mstr_standard
J 0
(1550 2275);
PAINT ORANGE (1550 2275);
DISPLAY INVISIBLE (1550 2275);
FORCEPROP 1 LAST COMMENT_BODY TRUE
J 0
(1500 2175);
DISPLAY 0.872340 (1500 2175);
PAINT GREEN (1500 2175);
DISPLAY INVISIBLE (1500 2175);
FORCEADD OFFPAGE..2
(1550 2125);
FORCEPROP 2 LAST $XR11 226 
J 0
(2219 2089);
DISPLAY 0.638298 (2219 2089);
PAINT MONO (2219 2089);
FORCEPROP 2 LAST $XR10 223 
J 0
(2099 2089);
DISPLAY 0.638298 (2099 2089);
PAINT MONO (2099 2089);
FORCEPROP 2 LAST $XR9 218 
J 0
(1979 2089);
DISPLAY 0.638298 (1979 2089);
PAINT MONO (1979 2089);
FORCEPROP 2 LAST $XR8 215 
J 0
(1859 2089);
DISPLAY 0.638298 (1859 2089);
PAINT MONO (1859 2089);
FORCEPROP 2 LAST $XR7 206 
J 0
(1739 2089);
DISPLAY 0.638298 (1739 2089);
PAINT MONO (1739 2089);
FORCEPROP 2 LAST $XR6 201 
J 0
(2459 2125);
DISPLAY 0.638298 (2459 2125);
PAINT MONO (2459 2125);
FORCEPROP 2 LAST $XR5 194 
J 0
(2339 2125);
DISPLAY 0.638298 (2339 2125);
PAINT MONO (2339 2125);
FORCEPROP 2 LAST $XR4 193 
J 0
(2219 2125);
DISPLAY 0.638298 (2219 2125);
PAINT MONO (2219 2125);
FORCEPROP 2 LAST $XR3 235 
J 0
(2099 2125);
DISPLAY 0.638298 (2099 2125);
PAINT MONO (2099 2125);
FORCEPROP 2 LAST $XR2 213 
J 0
(1979 2125);
DISPLAY 0.638298 (1979 2125);
PAINT MONO (1979 2125);
FORCEPROP 2 LAST $XR1 211 
J 0
(1859 2125);
DISPLAY 0.638298 (1859 2125);
PAINT MONO (1859 2125);
FORCEPROP 2 LAST $XR0 159 
J 0
(1739 2125);
DISPLAY 0.638298 (1739 2125);
PAINT MONO (1739 2125);
FORCEPROP 2 LAST PATH I50
J 0
(1775 2175);
DISPLAY 1.021277 (1775 2175);
PAINT ORANGE (1775 2175);
DISPLAY INVISIBLE (1775 2175);
FORCEPROP 2 LAST CDS_LIB mstr_standard
J 0
(1550 2125);
PAINT ORANGE (1550 2125);
DISPLAY INVISIBLE (1550 2125);
FORCEPROP 1 LAST COMMENT_BODY TRUE
J 0
(1505 2030);
DISPLAY 0.872340 (1505 2030);
PAINT GREEN (1505 2030);
DISPLAY INVISIBLE (1505 2030);
FORCEPROP 1 LAST OFFPAGE TRUE
J 0
(1875 2000);
DISPLAY 0.872340 (1875 2000);
PAINT GREEN (1875 2000);
DISPLAY INVISIBLE (1875 2000);
FORCEADD OFFPAGE..3
(-2150 4625);
FORCEPROP 2 LAST $XR0 156 
J 0
(-1936 4625);
DISPLAY 0.638298 (-1936 4625);
PAINT MONO (-1936 4625);
FORCEPROP 2 LAST $XR1 159 
J 0
(-1816 4625);
DISPLAY 0.638298 (-1816 4625);
PAINT MONO (-1816 4625);
FORCEPROP 2 LAST PATH I51
J 0
(-1925 4675);
DISPLAY 1.021277 (-1925 4675);
PAINT ORANGE (-1925 4675);
DISPLAY INVISIBLE (-1925 4675);
FORCEPROP 1 LAST OFFPAGE TRUE
J 0
(-1825 4500);
DISPLAY 0.872340 (-1825 4500);
PAINT GREEN (-1825 4500);
DISPLAY INVISIBLE (-1825 4500);
FORCEPROP 2 LAST CDS_LIB mstr_standard
J 0
(-2150 4625);
PAINT ORANGE (-2150 4625);
DISPLAY INVISIBLE (-2150 4625);
FORCEPROP 1 LAST COMMENT_BODY TRUE
J 0
(-2200 4525);
DISPLAY 0.872340 (-2200 4525);
PAINT GREEN (-2200 4525);
DISPLAY INVISIBLE (-2200 4525);
FORCEADD OFFPAGE..2
(-2150 4475);
FORCEPROP 2 LAST $XR1 156 
J 0
(-1841 4475);
DISPLAY 0.638298 (-1841 4475);
PAINT MONO (-1841 4475);
FORCEPROP 2 LAST $XR0 159 
J 0
(-1961 4475);
DISPLAY 0.638298 (-1961 4475);
PAINT MONO (-1961 4475);
FORCEPROP 1 LAST OFFPAGE TRUE
J 0
(-1825 4350);
DISPLAY 0.872340 (-1825 4350);
PAINT GREEN (-1825 4350);
DISPLAY INVISIBLE (-1825 4350);
FORCEPROP 2 LAST PATH I52
J 0
(-1925 4525);
DISPLAY 1.021277 (-1925 4525);
PAINT ORANGE (-1925 4525);
DISPLAY INVISIBLE (-1925 4525);
FORCEPROP 2 LAST CDS_LIB mstr_standard
J 0
(-2150 4475);
PAINT ORANGE (-2150 4475);
DISPLAY INVISIBLE (-2150 4475);
FORCEPROP 1 LAST COMMENT_BODY TRUE
J 0
(-2195 4380);
DISPLAY 0.872340 (-2195 4380);
PAINT GREEN (-2195 4380);
DISPLAY INVISIBLE (-2195 4380);
FORCEADD OFFPAGE..3
(-2150 3700);
FORCEPROP 2 LAST $XR4 159 
J 0
(-1456 3700);
DISPLAY 0.638298 (-1456 3700);
PAINT MONO (-1456 3700);
FORCEPROP 2 LAST $XR3 156 
J 0
(-1576 3700);
DISPLAY 0.638298 (-1576 3700);
PAINT MONO (-1576 3700);
FORCEPROP 2 LAST $XR0 101 
J 0
(-1936 3700);
DISPLAY 0.638298 (-1936 3700);
PAINT MONO (-1936 3700);
FORCEPROP 2 LAST $XR1 102 
J 0
(-1816 3700);
DISPLAY 0.638298 (-1816 3700);
PAINT MONO (-1816 3700);
FORCEPROP 2 LAST $XR2 111 
J 0
(-1696 3700);
DISPLAY 0.638298 (-1696 3700);
PAINT MONO (-1696 3700);
FORCEPROP 2 LAST $XR5 247 
J 0
(-1456 3700);
DISPLAY 0.638298 (-1456 3700);
PAINT MONO (-1456 3700);
FORCEPROP 2 LAST PATH I53
J 0
(-1925 3750);
DISPLAY 1.021277 (-1925 3750);
PAINT ORANGE (-1925 3750);
DISPLAY INVISIBLE (-1925 3750);
FORCEPROP 1 LAST OFFPAGE TRUE
J 0
(-1825 3575);
DISPLAY 0.872340 (-1825 3575);
PAINT GREEN (-1825 3575);
DISPLAY INVISIBLE (-1825 3575);
FORCEPROP 2 LAST CDS_LIB mstr_standard
J 0
(-2150 3700);
PAINT ORANGE (-2150 3700);
DISPLAY INVISIBLE (-2150 3700);
FORCEPROP 1 LAST COMMENT_BODY TRUE
J 0
(-2200 3600);
DISPLAY 0.872340 (-2200 3600);
PAINT GREEN (-2200 3600);
DISPLAY INVISIBLE (-2200 3600);
FORCEADD OFFPAGE..2
(-2150 3550);
FORCEPROP 2 LAST $XR0 159 
J 0
(-1961 3550);
DISPLAY 0.638298 (-1961 3550);
PAINT MONO (-1961 3550);
FORCEPROP 2 LAST $XR1 101 
J 0
(-1841 3550);
DISPLAY 0.638298 (-1841 3550);
PAINT MONO (-1841 3550);
FORCEPROP 2 LAST $XR4 156 
J 0
(-1481 3550);
DISPLAY 0.638298 (-1481 3550);
PAINT MONO (-1481 3550);
FORCEPROP 2 LAST $XR3 111 
J 0
(-1601 3550);
DISPLAY 0.638298 (-1601 3550);
PAINT MONO (-1601 3550);
FORCEPROP 2 LAST $XR2 102 
J 0
(-1721 3550);
DISPLAY 0.638298 (-1721 3550);
PAINT MONO (-1721 3550);
FORCEPROP 2 LAST $XR5 247 
J 0
(-1481 3550);
DISPLAY 0.638298 (-1481 3550);
PAINT MONO (-1481 3550);
FORCEPROP 2 LAST PATH I54
J 0
(-1925 3600);
DISPLAY 1.021277 (-1925 3600);
PAINT ORANGE (-1925 3600);
DISPLAY INVISIBLE (-1925 3600);
FORCEPROP 1 LAST OFFPAGE TRUE
J 0
(-1825 3425);
DISPLAY 0.872340 (-1825 3425);
PAINT GREEN (-1825 3425);
DISPLAY INVISIBLE (-1825 3425);
FORCEPROP 2 LAST CDS_LIB mstr_standard
J 0
(-2150 3550);
PAINT ORANGE (-2150 3550);
DISPLAY INVISIBLE (-2150 3550);
FORCEPROP 1 LAST COMMENT_BODY TRUE
J 0
(-2195 3455);
DISPLAY 0.872340 (-2195 3455);
PAINT GREEN (-2195 3455);
DISPLAY INVISIBLE (-2195 3455);
FORCEADD OFFPAGE..3
(-2125 2650);
FORCEPROP 2 LAST $XR0 108 
J 0
(-1911 2650);
DISPLAY 0.638298 (-1911 2650);
PAINT MONO (-1911 2650);
FORCEPROP 2 LAST $XR2 190 
J 0
(-1671 2650);
DISPLAY 0.638298 (-1671 2650);
PAINT MONO (-1671 2650);
FORCEPROP 2 LAST $XR1 183 
J 0
(-1791 2650);
DISPLAY 0.638298 (-1791 2650);
PAINT MONO (-1791 2650);
FORCEPROP 2 LAST PATH I57
J 0
(-1900 2700);
DISPLAY 1.021277 (-1900 2700);
PAINT ORANGE (-1900 2700);
DISPLAY INVISIBLE (-1900 2700);
FORCEPROP 1 LAST OFFPAGE TRUE
J 0
(-1800 2525);
DISPLAY 0.872340 (-1800 2525);
PAINT GREEN (-1800 2525);
DISPLAY INVISIBLE (-1800 2525);
FORCEPROP 2 LAST CDS_LIB mstr_standard
J 0
(-2125 2650);
PAINT ORANGE (-2125 2650);
DISPLAY INVISIBLE (-2125 2650);
FORCEPROP 1 LAST COMMENT_BODY TRUE
J 0
(-2175 2550);
DISPLAY 0.872340 (-2175 2550);
PAINT GREEN (-2175 2550);
DISPLAY INVISIBLE (-2175 2550);
FORCEADD OFFPAGE..2
(-2125 2500);
FORCEPROP 2 LAST $XR2 190 
J 0
(-1696 2500);
DISPLAY 0.638298 (-1696 2500);
PAINT MONO (-1696 2500);
FORCEPROP 2 LAST $XR1 183 
J 0
(-1816 2500);
DISPLAY 0.638298 (-1816 2500);
PAINT MONO (-1816 2500);
FORCEPROP 2 LAST $XR0 108 
J 0
(-1936 2500);
DISPLAY 0.638298 (-1936 2500);
PAINT MONO (-1936 2500);
FORCEPROP 2 LAST PATH I58
J 0
(-1900 2550);
DISPLAY 1.021277 (-1900 2550);
PAINT ORANGE (-1900 2550);
DISPLAY INVISIBLE (-1900 2550);
FORCEPROP 1 LAST OFFPAGE TRUE
J 0
(-1800 2375);
DISPLAY 0.872340 (-1800 2375);
PAINT GREEN (-1800 2375);
DISPLAY INVISIBLE (-1800 2375);
FORCEPROP 2 LAST CDS_LIB mstr_standard
J 0
(-2125 2500);
PAINT ORANGE (-2125 2500);
DISPLAY INVISIBLE (-2125 2500);
FORCEPROP 1 LAST COMMENT_BODY TRUE
J 0
(-2170 2405);
DISPLAY 0.872340 (-2170 2405);
PAINT GREEN (-2170 2405);
DISPLAY INVISIBLE (-2170 2405);
FORCEADD OFFPAGE..3
(-2125 1775);
FORCEPROP 2 LAST $XR1 160 
J 0
(-1791 1775);
DISPLAY 0.638298 (-1791 1775);
PAINT MONO (-1791 1775);
FORCEPROP 2 LAST $XR0 156 
J 0
(-1911 1775);
DISPLAY 0.638298 (-1911 1775);
PAINT MONO (-1911 1775);
FORCEPROP 2 LAST $XR3 ?
J 0
(-1671 1775);
DISPLAY 0.638298 (-1671 1775);
PAINT MONO (-1671 1775);
FORCEPROP 2 LAST $XR4 ?
J 0
(-1671 1775);
DISPLAY 0.638298 (-1671 1775);
PAINT MONO (-1671 1775);
FORCEPROP 2 LAST $XR2 182 
J 0
(-1671 1775);
DISPLAY 0.638298 (-1671 1775);
PAINT MONO (-1671 1775);
FORCEPROP 2 LAST PATH I59
J 0
(-1900 1825);
DISPLAY 1.021277 (-1900 1825);
PAINT ORANGE (-1900 1825);
DISPLAY INVISIBLE (-1900 1825);
FORCEPROP 1 LAST OFFPAGE TRUE
J 0
(-1800 1650);
DISPLAY 0.872340 (-1800 1650);
PAINT GREEN (-1800 1650);
DISPLAY INVISIBLE (-1800 1650);
FORCEPROP 2 LAST CDS_LIB mstr_standard
J 0
(-2125 1775);
PAINT ORANGE (-2125 1775);
DISPLAY INVISIBLE (-2125 1775);
FORCEPROP 1 LAST COMMENT_BODY TRUE
J 0
(-2175 1675);
DISPLAY 0.872340 (-2175 1675);
PAINT GREEN (-2175 1675);
DISPLAY INVISIBLE (-2175 1675);
FORCEADD OFFPAGE..2
(-2125 1625);
FORCEPROP 2 LAST $XR3 ?
J 0
(-1696 1625);
DISPLAY 0.638298 (-1696 1625);
PAINT MONO (-1696 1625);
FORCEPROP 2 LAST $XR4 ?
J 0
(-1696 1625);
DISPLAY 0.638298 (-1696 1625);
PAINT MONO (-1696 1625);
FORCEPROP 2 LAST $XR2 182 
J 0
(-1696 1625);
DISPLAY 0.638298 (-1696 1625);
PAINT MONO (-1696 1625);
FORCEPROP 2 LAST $XR1 156 
J 0
(-1816 1625);
DISPLAY 0.638298 (-1816 1625);
PAINT MONO (-1816 1625);
FORCEPROP 2 LAST $XR0 160 
J 0
(-1936 1625);
DISPLAY 0.638298 (-1936 1625);
PAINT MONO (-1936 1625);
FORCEPROP 2 LAST PATH I60
J 0
(-1900 1675);
DISPLAY 1.021277 (-1900 1675);
PAINT ORANGE (-1900 1675);
DISPLAY INVISIBLE (-1900 1675);
FORCEPROP 1 LAST OFFPAGE TRUE
J 0
(-1800 1500);
DISPLAY 0.872340 (-1800 1500);
PAINT GREEN (-1800 1500);
DISPLAY INVISIBLE (-1800 1500);
FORCEPROP 2 LAST CDS_LIB mstr_standard
J 0
(-2125 1625);
PAINT ORANGE (-2125 1625);
DISPLAY INVISIBLE (-2125 1625);
FORCEPROP 1 LAST COMMENT_BODY TRUE
J 0
(-2170 1530);
DISPLAY 0.872340 (-2170 1530);
PAINT GREEN (-2170 1530);
DISPLAY INVISIBLE (-2170 1530);
FORCEADD RES..2
(500 4450);
FORCEPROP 1 LAST TOLERANCE 1.0%
J 0
(545 4475);
DISPLAY 0.617021 (545 4475);
PAINT SKYBLUE (545 4475);
FORCEPROP 1 LAST MATERIAL CHIP
J 0
(540 4375);
DISPLAY 0.617021 (540 4375);
PAINT SKYBLUE (540 4375);
FORCEPROP 1 LAST VALUE 665
J 0
(545 4525);
DISPLAY 0.617021 (545 4525);
PAINT SKYBLUE (545 4525);
FORCEPROP 1 LASTPIN (500 4550) $PN 1
J 0
(505 4512);
DISPLAY 0.617021 (505 4512);
PAINT ORANGE (505 4512);
FORCEPROP 1 LASTPIN (500 4350) $PN 2
J 0
(505 4360);
DISPLAY 0.617021 (505 4360);
PAINT ORANGE (505 4360);
FORCEPROP 1 LAST WATTAGE 1/16W
J 0
(540 4425);
DISPLAY 0.617021 (540 4425);
PAINT SKYBLUE (540 4425);
FORCEPROP 1 LAST PACK_TYPE 0402
J 0
(540 4275);
DISPLAY 0.617021 (540 4275);
PAINT SKYBLUE (540 4275);
FORCEPROP 1 LAST PART_NUMBER G21796-235
J 0
(540 4325);
DISPLAY 0.617021 (540 4325);
PAINT BLUE (540 4325);
FORCEPROP 1 LAST LOCATION R2T53
J 0
(545 4575);
DISPLAY 0.617021 (545 4575);
PAINT AQUA (545 4575);
FORCEPROP 0 LAST BOM_COST SM_CONTROLLER
J 0
(550 4775);
DISPLAY 1.021277 (550 4775);
PAINT ORANGE (550 4775);
DISPLAY INVISIBLE (550 4775);
FORCEPROP 2 LAST SEC_TYPE 0402
J 0
(550 4675);
DISPLAY 1.021277 (550 4675);
PAINT ORANGE (550 4675);
DISPLAY INVISIBLE (550 4675);
FORCEPROP 2 LAST SEC 1
J 0
(550 4675);
PAINT MONO (550 4675);
DISPLAY INVISIBLE (550 4675);
FORCEPROP 1 LAST PATH I83
J 0
(550 4625);
DISPLAY 0.978723 (550 4625);
PAINT WHITE (550 4625);
DISPLAY INVISIBLE (550 4625);
FORCEPROP 0 LAST ROOM SMBUS
J 0
(550 4675);
DISPLAY 1.021277 (550 4675);
PAINT ORANGE (550 4675);
DISPLAY INVISIBLE (550 4675);
FORCEPROP 2 LAST CDS_LOCATION R2T53
J 0
(545 4575);
DISPLAY 0.617021 (545 4575);
PAINT AQUA (545 4575);
DISPLAY INVISIBLE (545 4575);
FORCEPROP 2 LAST CDS_LIB mstr_discrete
J 0
(500 4450);
PAINT ORANGE (500 4450);
DISPLAY INVISIBLE (500 4450);
FORCEADD RES..2
(850 4400);
FORCEPROP 1 LAST WATTAGE 1/16W
J 0
(890 4375);
DISPLAY 0.617021 (890 4375);
PAINT SKYBLUE (890 4375);
FORCEPROP 1 LAST PART_NUMBER G21796-235
J 0
(890 4275);
DISPLAY 0.617021 (890 4275);
PAINT BLUE (890 4275);
FORCEPROP 1 LAST LOCATION R2T54
J 0
(895 4525);
DISPLAY 0.617021 (895 4525);
PAINT AQUA (895 4525);
FORCEPROP 1 LASTPIN (850 4500) $PN 1
J 0
(855 4462);
DISPLAY 0.617021 (855 4462);
PAINT ORANGE (855 4462);
FORCEPROP 1 LAST TOLERANCE 1.0%
J 0
(895 4425);
DISPLAY 0.617021 (895 4425);
PAINT SKYBLUE (895 4425);
FORCEPROP 1 LAST VALUE 665
J 0
(895 4475);
DISPLAY 0.617021 (895 4475);
PAINT SKYBLUE (895 4475);
FORCEPROP 1 LASTPIN (850 4300) $PN 2
J 0
(855 4310);
DISPLAY 0.617021 (855 4310);
PAINT ORANGE (855 4310);
FORCEPROP 1 LAST MATERIAL CHIP
J 0
(890 4325);
DISPLAY 0.617021 (890 4325);
PAINT SKYBLUE (890 4325);
FORCEPROP 1 LAST PACK_TYPE 0402
J 0
(890 4225);
DISPLAY 0.617021 (890 4225);
PAINT SKYBLUE (890 4225);
FORCEPROP 0 LAST BOM_COST SM_CONTROLLER
J 0
(900 4725);
DISPLAY 1.021277 (900 4725);
PAINT ORANGE (900 4725);
DISPLAY INVISIBLE (900 4725);
FORCEPROP 2 LAST SEC_TYPE 0402
J 0
(900 4625);
DISPLAY 1.021277 (900 4625);
PAINT ORANGE (900 4625);
DISPLAY INVISIBLE (900 4625);
FORCEPROP 2 LAST SEC 1
J 0
(900 4625);
PAINT MONO (900 4625);
DISPLAY INVISIBLE (900 4625);
FORCEPROP 0 LAST ROOM SMBUS
J 0
(900 4625);
DISPLAY 1.021277 (900 4625);
PAINT ORANGE (900 4625);
DISPLAY INVISIBLE (900 4625);
FORCEPROP 1 LAST PATH I84
J 0
(900 4575);
DISPLAY 0.978723 (900 4575);
PAINT WHITE (900 4575);
DISPLAY INVISIBLE (900 4575);
FORCEPROP 2 LAST CDS_LOCATION R2T54
J 0
(895 4525);
DISPLAY 0.617021 (895 4525);
PAINT AQUA (895 4525);
DISPLAY INVISIBLE (895 4525);
FORCEPROP 2 LAST CDS_LIB mstr_discrete
J 0
(850 4400);
PAINT ORANGE (850 4400);
DISPLAY INVISIBLE (850 4400);
FORCEADD RES..2
(500 2575);
FORCEPROP 1 LAST LOCATION R8D17
J 0
(545 2700);
DISPLAY 0.617021 (545 2700);
PAINT AQUA (545 2700);
FORCEPROP 1 LAST VALUE 1.37K
J 0
(545 2650);
DISPLAY 0.617021 (545 2650);
PAINT SKYBLUE (545 2650);
FORCEPROP 1 LAST WATTAGE 1/16W
J 0
(540 2550);
DISPLAY 0.617021 (540 2550);
PAINT SKYBLUE (540 2550);
FORCEPROP 1 LAST PART_NUMBER G21796-095
J 0
(540 2450);
DISPLAY 0.617021 (540 2450);
PAINT BLUE (540 2450);
FORCEPROP 1 LAST MATERIAL CHIP
J 0
(540 2500);
DISPLAY 0.617021 (540 2500);
PAINT SKYBLUE (540 2500);
FORCEPROP 1 LAST PACK_TYPE 0402
J 0
(540 2400);
DISPLAY 0.617021 (540 2400);
PAINT SKYBLUE (540 2400);
FORCEPROP 1 LAST TOLERANCE 1%
J 0
(545 2600);
DISPLAY 0.617021 (545 2600);
PAINT SKYBLUE (545 2600);
FORCEPROP 0 LAST ROOM SMBUS
J 0
(550 2800);
DISPLAY 1.021277 (550 2800);
PAINT ORANGE (550 2800);
DISPLAY INVISIBLE (550 2800);
FORCEPROP 1 LAST PATH I87
J 0
(550 2750);
DISPLAY 0.978723 (550 2750);
PAINT WHITE (550 2750);
DISPLAY INVISIBLE (550 2750);
FORCEPROP 2 LAST CDS_LOCATION R8D17
J 0
(545 2700);
DISPLAY 0.617021 (545 2700);
PAINT AQUA (545 2700);
DISPLAY INVISIBLE (545 2700);
FORCEPROP 0 LAST BOM_COST SM_CONTROLLER
J 0
(550 2900);
DISPLAY 1.021277 (550 2900);
PAINT ORANGE (550 2900);
DISPLAY INVISIBLE (550 2900);
FORCEPROP 2 LAST CDS_LIB mstr_discrete
J 0
(500 2575);
PAINT ORANGE (500 2575);
DISPLAY INVISIBLE (500 2575);
FORCEPROP 1 LASTPIN (500 2675) $PN 1
J 0
(505 2637);
DISPLAY 0.787234 (505 2637);
PAINT ORANGE (505 2637);
DISPLAY INVISIBLE (505 2637);
FORCEPROP 1 LASTPIN (500 2475) $PN 2
J 0
(505 2485);
DISPLAY 0.787234 (505 2485);
PAINT ORANGE (505 2485);
DISPLAY INVISIBLE (505 2485);
FORCEADD RES..2
(875 2525);
FORCEPROP 1 LAST WATTAGE 1/16W
J 0
(915 2500);
DISPLAY 0.617021 (915 2500);
PAINT SKYBLUE (915 2500);
FORCEPROP 1 LAST MATERIAL CHIP
J 0
(915 2450);
DISPLAY 0.617021 (915 2450);
PAINT SKYBLUE (915 2450);
FORCEPROP 1 LAST PACK_TYPE 0402
J 0
(915 2350);
DISPLAY 0.617021 (915 2350);
PAINT SKYBLUE (915 2350);
FORCEPROP 1 LAST VALUE 1.37K
J 0
(920 2600);
DISPLAY 0.617021 (920 2600);
PAINT SKYBLUE (920 2600);
FORCEPROP 1 LAST PART_NUMBER G21796-095
J 0
(915 2400);
DISPLAY 0.617021 (915 2400);
PAINT BLUE (915 2400);
FORCEPROP 1 LAST TOLERANCE 1%
J 0
(920 2550);
DISPLAY 0.617021 (920 2550);
PAINT SKYBLUE (920 2550);
FORCEPROP 1 LAST LOCATION R8D15
J 0
(920 2650);
DISPLAY 0.617021 (920 2650);
PAINT AQUA (920 2650);
FORCEPROP 0 LAST BOM_COST SM_CONTROLLER
J 0
(925 2850);
DISPLAY 1.021277 (925 2850);
PAINT ORANGE (925 2850);
DISPLAY INVISIBLE (925 2850);
FORCEPROP 2 LAST CDS_LOCATION R8D15
J 0
(920 2650);
DISPLAY 0.617021 (920 2650);
PAINT AQUA (920 2650);
DISPLAY INVISIBLE (920 2650);
FORCEPROP 1 LAST PATH I88
J 0
(925 2700);
DISPLAY 0.978723 (925 2700);
PAINT WHITE (925 2700);
DISPLAY INVISIBLE (925 2700);
FORCEPROP 0 LAST ROOM SMBUS
J 0
(925 2750);
DISPLAY 1.021277 (925 2750);
PAINT ORANGE (925 2750);
DISPLAY INVISIBLE (925 2750);
FORCEPROP 1 LASTPIN (875 2625) $PN 1
J 0
(880 2587);
DISPLAY 0.787234 (880 2587);
PAINT ORANGE (880 2587);
DISPLAY INVISIBLE (880 2587);
FORCEPROP 2 LAST CDS_LIB mstr_discrete
J 0
(875 2525);
PAINT ORANGE (875 2525);
DISPLAY INVISIBLE (875 2525);
FORCEPROP 1 LASTPIN (875 2425) $PN 2
J 0
(880 2435);
DISPLAY 0.787234 (880 2435);
PAINT ORANGE (880 2435);
DISPLAY INVISIBLE (880 2435);
FORCEADD RES..2
(-3175 4950);
FORCEPROP 1 LAST WATTAGE 1/16W
J 0
(-3135 4925);
DISPLAY 0.617021 (-3135 4925);
PAINT SKYBLUE (-3135 4925);
FORCEPROP 1 LAST MATERIAL CHIP
J 0
(-3135 4875);
DISPLAY 0.617021 (-3135 4875);
PAINT SKYBLUE (-3135 4875);
FORCEPROP 1 LAST PACK_TYPE 0402
J 0
(-3135 4775);
DISPLAY 0.617021 (-3135 4775);
PAINT SKYBLUE (-3135 4775);
FORCEPROP 1 LAST TOLERANCE 1.0%
J 0
(-3130 4975);
DISPLAY 0.617021 (-3130 4975);
PAINT SKYBLUE (-3130 4975);
FORCEPROP 1 LAST VALUE 665
J 0
(-3130 5025);
DISPLAY 0.617021 (-3130 5025);
PAINT SKYBLUE (-3130 5025);
FORCEPROP 1 LAST PART_NUMBER G21796-235
J 0
(-3135 4825);
DISPLAY 0.617021 (-3135 4825);
PAINT BLUE (-3135 4825);
FORCEPROP 1 LAST LOCATION R2N8
J 0
(-3130 5075);
DISPLAY 0.617021 (-3130 5075);
PAINT AQUA (-3130 5075);
FORCEPROP 1 LASTPIN (-3175 5050) $PN 1
J 0
(-3170 5012);
DISPLAY 0.617021 (-3170 5012);
PAINT ORANGE (-3170 5012);
FORCEPROP 1 LASTPIN (-3175 4850) $PN 2
J 0
(-3170 4860);
DISPLAY 0.617021 (-3170 4860);
PAINT ORANGE (-3170 4860);
FORCEPROP 2 LAST BOM_COST SM_CONTROLLER
J 0
(-3125 5275);
DISPLAY 1.021277 (-3125 5275);
PAINT ORANGE (-3125 5275);
DISPLAY INVISIBLE (-3125 5275);
FORCEPROP 2 LAST SEC_TYPE 0402
J 0
(-3125 5175);
DISPLAY 1.021277 (-3125 5175);
PAINT ORANGE (-3125 5175);
DISPLAY INVISIBLE (-3125 5175);
FORCEPROP 2 LAST SEC 1
J 0
(-3125 5175);
PAINT MONO (-3125 5175);
DISPLAY INVISIBLE (-3125 5175);
FORCEPROP 1 LAST PATH I89
J 0
(-3125 5125);
DISPLAY 0.978723 (-3125 5125);
PAINT WHITE (-3125 5125);
DISPLAY INVISIBLE (-3125 5125);
FORCEPROP 2 LAST ROOM SMBUS
J 0
(-3125 5175);
DISPLAY 1.021277 (-3125 5175);
PAINT ORANGE (-3125 5175);
DISPLAY INVISIBLE (-3125 5175);
FORCEPROP 2 LAST CDS_LOCATION R2N8
J 0
(-3130 5075);
DISPLAY 0.617021 (-3130 5075);
PAINT AQUA (-3130 5075);
DISPLAY INVISIBLE (-3130 5075);
FORCEPROP 2 LAST CDS_LIB mstr_discrete
J 0
(-3175 4950);
PAINT ORANGE (-3175 4950);
DISPLAY INVISIBLE (-3175 4950);
FORCEADD RES..2
(-2775 4900);
FORCEPROP 1 LAST TOLERANCE 1.0%
J 0
(-2730 4925);
DISPLAY 0.617021 (-2730 4925);
PAINT SKYBLUE (-2730 4925);
FORCEPROP 1 LAST VALUE 665
J 0
(-2730 4975);
DISPLAY 0.617021 (-2730 4975);
PAINT SKYBLUE (-2730 4975);
FORCEPROP 1 LAST WATTAGE 1/16W
J 0
(-2735 4875);
DISPLAY 0.617021 (-2735 4875);
PAINT SKYBLUE (-2735 4875);
FORCEPROP 1 LASTPIN (-2775 5000) $PN 1
J 0
(-2770 4962);
DISPLAY 0.617021 (-2770 4962);
PAINT ORANGE (-2770 4962);
FORCEPROP 1 LASTPIN (-2775 4800) $PN 2
J 0
(-2770 4810);
DISPLAY 0.617021 (-2770 4810);
PAINT ORANGE (-2770 4810);
FORCEPROP 1 LAST MATERIAL CHIP
J 0
(-2735 4825);
DISPLAY 0.617021 (-2735 4825);
PAINT SKYBLUE (-2735 4825);
FORCEPROP 1 LAST PACK_TYPE 0402
J 0
(-2735 4725);
DISPLAY 0.617021 (-2735 4725);
PAINT SKYBLUE (-2735 4725);
FORCEPROP 1 LAST PART_NUMBER G21796-235
J 0
(-2735 4775);
DISPLAY 0.617021 (-2735 4775);
PAINT BLUE (-2735 4775);
FORCEPROP 1 LAST LOCATION R2N5
J 0
(-2730 5025);
DISPLAY 0.617021 (-2730 5025);
PAINT AQUA (-2730 5025);
FORCEPROP 2 LAST SEC 1
J 0
(-2725 5125);
PAINT MONO (-2725 5125);
DISPLAY INVISIBLE (-2725 5125);
FORCEPROP 2 LAST SEC_TYPE 0402
J 0
(-2725 5125);
DISPLAY 1.021277 (-2725 5125);
PAINT ORANGE (-2725 5125);
DISPLAY INVISIBLE (-2725 5125);
FORCEPROP 2 LAST BOM_COST SM_CONTROLLER
J 0
(-2725 5225);
DISPLAY 1.021277 (-2725 5225);
PAINT ORANGE (-2725 5225);
DISPLAY INVISIBLE (-2725 5225);
FORCEPROP 2 LAST ROOM SMBUS
J 0
(-2725 5125);
DISPLAY 1.021277 (-2725 5125);
PAINT ORANGE (-2725 5125);
DISPLAY INVISIBLE (-2725 5125);
FORCEPROP 1 LAST PATH I90
J 0
(-2725 5075);
DISPLAY 0.978723 (-2725 5075);
PAINT WHITE (-2725 5075);
DISPLAY INVISIBLE (-2725 5075);
FORCEPROP 2 LAST CDS_LOCATION R2N5
J 0
(-2730 5025);
DISPLAY 0.617021 (-2730 5025);
PAINT AQUA (-2730 5025);
DISPLAY INVISIBLE (-2730 5025);
FORCEPROP 2 LAST CDS_LIB mstr_discrete
J 0
(-2775 4900);
PAINT ORANGE (-2775 4900);
DISPLAY INVISIBLE (-2775 4900);
FORCEADD RES..2
(-3175 4025);
FORCEPROP 1 LAST VALUE 2.0K
J 0
(-3130 4100);
DISPLAY 0.617021 (-3130 4100);
PAINT SKYBLUE (-3130 4100);
FORCEPROP 1 LAST LOCATION R8C16
J 0
(-3130 4150);
DISPLAY 0.617021 (-3130 4150);
PAINT AQUA (-3130 4150);
FORCEPROP 1 LAST WATTAGE 1/16W
J 0
(-3135 4000);
DISPLAY 0.617021 (-3135 4000);
PAINT SKYBLUE (-3135 4000);
FORCEPROP 1 LAST MATERIAL CHIP
J 0
(-3135 3950);
DISPLAY 0.617021 (-3135 3950);
PAINT SKYBLUE (-3135 3950);
FORCEPROP 1 LAST PACK_TYPE 0402
J 0
(-3135 3850);
DISPLAY 0.617021 (-3135 3850);
PAINT SKYBLUE (-3135 3850);
FORCEPROP 1 LAST TOLERANCE 1%
J 0
(-3130 4050);
DISPLAY 0.617021 (-3130 4050);
PAINT SKYBLUE (-3130 4050);
FORCEPROP 1 LAST PART_NUMBER G21796-001
J 0
(-3135 3900);
DISPLAY 0.617021 (-3135 3900);
PAINT BLUE (-3135 3900);
FORCEPROP 2 LAST BOM_COST SM_CONTROLLER
J 0
(-3125 4350);
DISPLAY 1.021277 (-3125 4350);
PAINT ORANGE (-3125 4350);
DISPLAY INVISIBLE (-3125 4350);
FORCEPROP 1 LAST PATH I91
J 0
(-3125 4200);
DISPLAY 0.978723 (-3125 4200);
PAINT WHITE (-3125 4200);
DISPLAY INVISIBLE (-3125 4200);
FORCEPROP 2 LAST CDS_LOCATION R8C16
J 0
(-3130 4150);
DISPLAY 0.617021 (-3130 4150);
PAINT AQUA (-3130 4150);
DISPLAY INVISIBLE (-3130 4150);
FORCEPROP 2 LAST ROOM SMBUS
J 0
(-3125 4250);
DISPLAY 1.021277 (-3125 4250);
PAINT ORANGE (-3125 4250);
DISPLAY INVISIBLE (-3125 4250);
FORCEPROP 1 LASTPIN (-3175 4125) $PN 1
J 0
(-3170 4087);
DISPLAY 0.787234 (-3170 4087);
PAINT ORANGE (-3170 4087);
DISPLAY INVISIBLE (-3170 4087);
FORCEPROP 2 LAST CDS_LIB mstr_discrete
J 0
(-3175 4025);
PAINT ORANGE (-3175 4025);
DISPLAY INVISIBLE (-3175 4025);
FORCEPROP 1 LASTPIN (-3175 3925) $PN 2
J 0
(-3170 3935);
DISPLAY 0.787234 (-3170 3935);
PAINT ORANGE (-3170 3935);
DISPLAY INVISIBLE (-3170 3935);
FORCEADD RES..2
(-2775 3975);
FORCEPROP 1 LAST LOCATION R8C15
J 0
(-2730 4100);
DISPLAY 0.617021 (-2730 4100);
PAINT AQUA (-2730 4100);
FORCEPROP 1 LAST PART_NUMBER G21796-001
J 0
(-2735 3850);
DISPLAY 0.617021 (-2735 3850);
PAINT BLUE (-2735 3850);
FORCEPROP 1 LAST TOLERANCE 1%
J 0
(-2730 4000);
DISPLAY 0.617021 (-2730 4000);
PAINT SKYBLUE (-2730 4000);
FORCEPROP 1 LAST VALUE 2.0K
J 0
(-2730 4050);
DISPLAY 0.617021 (-2730 4050);
PAINT SKYBLUE (-2730 4050);
FORCEPROP 1 LAST MATERIAL CHIP
J 0
(-2735 3900);
DISPLAY 0.617021 (-2735 3900);
PAINT SKYBLUE (-2735 3900);
FORCEPROP 1 LAST WATTAGE 1/16W
J 0
(-2735 3950);
DISPLAY 0.617021 (-2735 3950);
PAINT SKYBLUE (-2735 3950);
FORCEPROP 1 LAST PACK_TYPE 0402
J 0
(-2735 3800);
DISPLAY 0.617021 (-2735 3800);
PAINT SKYBLUE (-2735 3800);
FORCEPROP 1 LAST PATH I92
J 0
(-2725 4150);
DISPLAY 0.978723 (-2725 4150);
PAINT WHITE (-2725 4150);
DISPLAY INVISIBLE (-2725 4150);
FORCEPROP 2 LAST CDS_LOCATION R8C15
J 0
(-2730 4100);
DISPLAY 0.617021 (-2730 4100);
PAINT AQUA (-2730 4100);
DISPLAY INVISIBLE (-2730 4100);
FORCEPROP 2 LAST BOM_COST SM_CONTROLLER
J 0
(-2725 4300);
DISPLAY 1.021277 (-2725 4300);
PAINT ORANGE (-2725 4300);
DISPLAY INVISIBLE (-2725 4300);
FORCEPROP 2 LAST ROOM SMBUS
J 0
(-2725 4200);
DISPLAY 1.021277 (-2725 4200);
PAINT ORANGE (-2725 4200);
DISPLAY INVISIBLE (-2725 4200);
FORCEPROP 1 LASTPIN (-2775 4075) $PN 1
J 0
(-2770 4037);
DISPLAY 0.787234 (-2770 4037);
PAINT ORANGE (-2770 4037);
DISPLAY INVISIBLE (-2770 4037);
FORCEPROP 2 LAST CDS_LIB mstr_discrete
J 0
(-2775 3975);
PAINT ORANGE (-2775 3975);
DISPLAY INVISIBLE (-2775 3975);
FORCEPROP 1 LASTPIN (-2775 3875) $PN 2
J 0
(-2770 3885);
DISPLAY 0.787234 (-2770 3885);
PAINT ORANGE (-2770 3885);
DISPLAY INVISIBLE (-2770 3885);
FORCEADD RES..2
(-3150 2950);
FORCEPROP 1 LAST LOCATION R8B24
J 0
(-3105 3075);
DISPLAY 0.617021 (-3105 3075);
PAINT AQUA (-3105 3075);
FORCEPROP 1 LAST WATTAGE 1/16W
J 0
(-3110 2925);
DISPLAY 0.617021 (-3110 2925);
PAINT SKYBLUE (-3110 2925);
FORCEPROP 1 LAST MATERIAL CHIP
J 0
(-3110 2875);
DISPLAY 0.617021 (-3110 2875);
PAINT SKYBLUE (-3110 2875);
FORCEPROP 1 LAST PACK_TYPE 0402
J 0
(-3110 2775);
DISPLAY 0.617021 (-3110 2775);
PAINT SKYBLUE (-3110 2775);
FORCEPROP 1 LAST TOLERANCE 5%
J 0
(-3105 2975);
DISPLAY 0.617021 (-3105 2975);
PAINT SKYBLUE (-3105 2975);
FORCEPROP 1 LAST VALUE 3.3K
J 0
(-3105 3025);
DISPLAY 0.617021 (-3105 3025);
PAINT SKYBLUE (-3105 3025);
FORCEPROP 1 LAST PART_NUMBER G21497-013
J 0
(-3110 2825);
DISPLAY 0.617021 (-3110 2825);
PAINT BLUE (-3110 2825);
FORCEPROP 1 LASTPIN (-3150 3050) $PN 1
J 0
(-3145 3012);
DISPLAY 0.617021 (-3145 3012);
PAINT ORANGE (-3145 3012);
FORCEPROP 1 LASTPIN (-3150 2850) $PN 2
J 0
(-3145 2860);
DISPLAY 0.617021 (-3145 2860);
PAINT ORANGE (-3145 2860);
FORCEPROP 0 LAST BOM_COST SM_CONTROLLER
J 0
(-3100 3275);
DISPLAY 1.021277 (-3100 3275);
PAINT ORANGE (-3100 3275);
DISPLAY INVISIBLE (-3100 3275);
FORCEPROP 2 LAST SEC 1
J 0
(-3100 3175);
PAINT MONO (-3100 3175);
DISPLAY INVISIBLE (-3100 3175);
FORCEPROP 2 LAST SEC_TYPE 0402
J 0
(-3100 3175);
DISPLAY 1.021277 (-3100 3175);
PAINT ORANGE (-3100 3175);
DISPLAY INVISIBLE (-3100 3175);
FORCEPROP 0 LAST ROOM SMBUS
J 0
(-3100 3175);
DISPLAY 1.021277 (-3100 3175);
PAINT ORANGE (-3100 3175);
DISPLAY INVISIBLE (-3100 3175);
FORCEPROP 2 LAST CDS_LOCATION R8B24
J 0
(-3105 3075);
DISPLAY 0.617021 (-3105 3075);
PAINT AQUA (-3105 3075);
DISPLAY INVISIBLE (-3105 3075);
FORCEPROP 1 LAST PATH I95
J 0
(-3100 3125);
DISPLAY 0.978723 (-3100 3125);
PAINT WHITE (-3100 3125);
DISPLAY INVISIBLE (-3100 3125);
FORCEPROP 2 LAST CDS_LIB mstr_discrete
J 0
(-3150 2950);
PAINT MONO (-3150 2950);
DISPLAY INVISIBLE (-3150 2950);
FORCEADD RES..2
(-2750 2925);
FORCEPROP 1 LAST PART_NUMBER G21497-013
J 0
(-2710 2800);
DISPLAY 0.617021 (-2710 2800);
PAINT BLUE (-2710 2800);
FORCEPROP 1 LAST LOCATION R8B26
J 0
(-2705 3050);
DISPLAY 0.617021 (-2705 3050);
PAINT AQUA (-2705 3050);
FORCEPROP 1 LAST VALUE 3.3K
J 0
(-2705 3000);
DISPLAY 0.617021 (-2705 3000);
PAINT SKYBLUE (-2705 3000);
FORCEPROP 1 LAST WATTAGE 1/16W
J 0
(-2710 2900);
DISPLAY 0.617021 (-2710 2900);
PAINT SKYBLUE (-2710 2900);
FORCEPROP 1 LAST MATERIAL CHIP
J 0
(-2710 2850);
DISPLAY 0.617021 (-2710 2850);
PAINT SKYBLUE (-2710 2850);
FORCEPROP 1 LAST TOLERANCE 5%
J 0
(-2705 2950);
DISPLAY 0.617021 (-2705 2950);
PAINT SKYBLUE (-2705 2950);
FORCEPROP 1 LASTPIN (-2750 3025) $PN 1
J 0
(-2745 2987);
DISPLAY 0.617021 (-2745 2987);
PAINT ORANGE (-2745 2987);
FORCEPROP 1 LASTPIN (-2750 2825) $PN 2
J 0
(-2745 2835);
DISPLAY 0.617021 (-2745 2835);
PAINT ORANGE (-2745 2835);
FORCEPROP 1 LAST PACK_TYPE 0402
J 0
(-2710 2750);
DISPLAY 0.617021 (-2710 2750);
PAINT SKYBLUE (-2710 2750);
FORCEPROP 1 LAST PATH I96
J 0
(-2700 3100);
DISPLAY 0.978723 (-2700 3100);
PAINT WHITE (-2700 3100);
DISPLAY INVISIBLE (-2700 3100);
FORCEPROP 2 LAST SEC 1
J 0
(-2700 3150);
PAINT MONO (-2700 3150);
DISPLAY INVISIBLE (-2700 3150);
FORCEPROP 0 LAST BOM_COST SM_CONTROLLER
J 0
(-2700 3250);
DISPLAY 1.021277 (-2700 3250);
PAINT ORANGE (-2700 3250);
DISPLAY INVISIBLE (-2700 3250);
FORCEPROP 2 LAST SEC_TYPE 0402
J 0
(-2700 3150);
DISPLAY 1.021277 (-2700 3150);
PAINT ORANGE (-2700 3150);
DISPLAY INVISIBLE (-2700 3150);
FORCEPROP 0 LAST ROOM SMBUS
J 0
(-2700 3150);
DISPLAY 1.021277 (-2700 3150);
PAINT ORANGE (-2700 3150);
DISPLAY INVISIBLE (-2700 3150);
FORCEPROP 2 LAST CDS_LOCATION R8B26
J 0
(-2705 3050);
DISPLAY 0.617021 (-2705 3050);
PAINT AQUA (-2705 3050);
DISPLAY INVISIBLE (-2705 3050);
FORCEPROP 2 LAST CDS_LIB mstr_discrete
J 0
(-2750 2925);
PAINT MONO (-2750 2925);
DISPLAY INVISIBLE (-2750 2925);
FORCEADD RES..2
(-3150 2100);
FORCEPROP 1 LASTPIN (-3150 2200) $PN 1
J 0
(-3145 2162);
DISPLAY 0.617021 (-3145 2162);
PAINT ORANGE (-3145 2162);
FORCEPROP 1 LAST LOCATION R2U11
J 0
(-3105 2225);
DISPLAY 0.617021 (-3105 2225);
PAINT AQUA (-3105 2225);
FORCEPROP 1 LAST WATTAGE 1/16W
J 0
(-3110 2075);
DISPLAY 0.617021 (-3110 2075);
PAINT SKYBLUE (-3110 2075);
FORCEPROP 1 LAST TOLERANCE 1.0%
J 0
(-3105 2125);
DISPLAY 0.617021 (-3105 2125);
PAINT SKYBLUE (-3105 2125);
FORCEPROP 1 LAST VALUE 665
J 0
(-3105 2175);
DISPLAY 0.617021 (-3105 2175);
PAINT SKYBLUE (-3105 2175);
FORCEPROP 1 LAST MATERIAL CHIP
J 0
(-3110 2025);
DISPLAY 0.617021 (-3110 2025);
PAINT SKYBLUE (-3110 2025);
FORCEPROP 1 LAST PART_NUMBER G21796-235
J 0
(-3110 1975);
DISPLAY 0.617021 (-3110 1975);
PAINT BLUE (-3110 1975);
FORCEPROP 1 LASTPIN (-3150 2000) $PN 2
J 0
(-3145 2010);
DISPLAY 0.617021 (-3145 2010);
PAINT ORANGE (-3145 2010);
FORCEPROP 1 LAST PACK_TYPE 0402
J 0
(-3110 1925);
DISPLAY 0.617021 (-3110 1925);
PAINT SKYBLUE (-3110 1925);
FORCEPROP 2 LAST SEC 1
J 0
(-3100 2325);
PAINT MONO (-3100 2325);
DISPLAY INVISIBLE (-3100 2325);
FORCEPROP 2 LAST SEC_TYPE 0402
J 0
(-3100 2325);
DISPLAY 1.021277 (-3100 2325);
PAINT ORANGE (-3100 2325);
DISPLAY INVISIBLE (-3100 2325);
FORCEPROP 0 LAST BOM_COST SM_CONTROLLER
J 0
(-3100 2425);
DISPLAY 1.021277 (-3100 2425);
PAINT ORANGE (-3100 2425);
DISPLAY INVISIBLE (-3100 2425);
FORCEPROP 0 LAST ROOM SMBUS
J 0
(-3100 2325);
DISPLAY 1.021277 (-3100 2325);
PAINT ORANGE (-3100 2325);
DISPLAY INVISIBLE (-3100 2325);
FORCEPROP 1 LAST PATH I97
J 0
(-3100 2275);
DISPLAY 0.978723 (-3100 2275);
PAINT WHITE (-3100 2275);
DISPLAY INVISIBLE (-3100 2275);
FORCEPROP 2 LAST CDS_LOCATION R2U11
J 0
(-3105 2225);
DISPLAY 0.617021 (-3105 2225);
PAINT AQUA (-3105 2225);
DISPLAY INVISIBLE (-3105 2225);
FORCEPROP 2 LAST CDS_LIB mstr_discrete
J 0
(-3150 2100);
PAINT ORANGE (-3150 2100);
DISPLAY INVISIBLE (-3150 2100);
FORCEADD RES..2
(-2750 2025);
FORCEPROP 1 LAST VALUE 665
J 0
(-2705 2100);
DISPLAY 0.617021 (-2705 2100);
PAINT SKYBLUE (-2705 2100);
FORCEPROP 1 LAST LOCATION R2U3
J 0
(-2705 2150);
DISPLAY 0.617021 (-2705 2150);
PAINT AQUA (-2705 2150);
FORCEPROP 1 LAST TOLERANCE 1.0%
J 0
(-2705 2050);
DISPLAY 0.617021 (-2705 2050);
PAINT SKYBLUE (-2705 2050);
FORCEPROP 1 LASTPIN (-2750 2125) $PN 1
J 0
(-2745 2087);
DISPLAY 0.617021 (-2745 2087);
PAINT ORANGE (-2745 2087);
FORCEPROP 1 LASTPIN (-2750 1925) $PN 2
J 0
(-2745 1935);
DISPLAY 0.617021 (-2745 1935);
PAINT ORANGE (-2745 1935);
FORCEPROP 1 LAST WATTAGE 1/16W
J 0
(-2710 2000);
DISPLAY 0.617021 (-2710 2000);
PAINT SKYBLUE (-2710 2000);
FORCEPROP 1 LAST MATERIAL CHIP
J 0
(-2710 1950);
DISPLAY 0.617021 (-2710 1950);
PAINT SKYBLUE (-2710 1950);
FORCEPROP 1 LAST PACK_TYPE 0402
J 0
(-2710 1850);
DISPLAY 0.617021 (-2710 1850);
PAINT SKYBLUE (-2710 1850);
FORCEPROP 1 LAST PART_NUMBER G21796-235
J 0
(-2710 1900);
DISPLAY 0.617021 (-2710 1900);
PAINT BLUE (-2710 1900);
FORCEPROP 0 LAST BOM_COST SM_CONTROLLER
J 0
(-2700 2350);
DISPLAY 1.021277 (-2700 2350);
PAINT ORANGE (-2700 2350);
DISPLAY INVISIBLE (-2700 2350);
FORCEPROP 2 LAST SEC_TYPE 0402
J 0
(-2700 2250);
DISPLAY 1.021277 (-2700 2250);
PAINT ORANGE (-2700 2250);
DISPLAY INVISIBLE (-2700 2250);
FORCEPROP 1 LAST PATH I98
J 0
(-2700 2200);
DISPLAY 0.978723 (-2700 2200);
PAINT WHITE (-2700 2200);
DISPLAY INVISIBLE (-2700 2200);
FORCEPROP 0 LAST ROOM SMBUS
J 0
(-2700 2250);
DISPLAY 1.021277 (-2700 2250);
PAINT ORANGE (-2700 2250);
DISPLAY INVISIBLE (-2700 2250);
FORCEPROP 2 LAST SEC 1
J 0
(-2700 2250);
PAINT MONO (-2700 2250);
DISPLAY INVISIBLE (-2700 2250);
FORCEPROP 2 LAST CDS_LOCATION R2U3
J 0
(-2705 2150);
DISPLAY 0.617021 (-2705 2150);
PAINT AQUA (-2705 2150);
DISPLAY INVISIBLE (-2705 2150);
FORCEPROP 2 LAST CDS_LIB mstr_discrete
J 0
(-2750 2025);
PAINT ORANGE (-2750 2025);
DISPLAY INVISIBLE (-2750 2025);
FORCEADD DESIGN_NOTE..1
(-4950 1425);
FORCEPROP 0 LAST L2 IF CONCLUSION IS IT'S NEEDED
J 0
(-5150 1275);
DISPLAY 0.808511 (-5150 1275);
PAINT ORANGE (-5150 1275);
FORCEPROP 0 LAST L1 WILL ADD OTHER STEERING RESISTORS
J 0
(-5150 1325);
DISPLAY 0.808511 (-5150 1325);
PAINT ORANGE (-5150 1325);
FORCEPROP 0 LAST L3 AFTER LAYOUT IS DONE
J 0
(-5150 1225);
DISPLAY 0.808511 (-5150 1225);
PAINT ORANGE (-5150 1225);
FORCEPROP 1 LAST COMMENT_BODY TRUE
J 0
(-4925 1525);
DISPLAY 0.978723 (-4925 1525);
PAINT ORANGE (-4925 1525);
DISPLAY INVISIBLE (-4925 1525);
FORCEPROP 2 LAST CDS_LIB mstr_symbols
J 0
(-4950 1425);
PAINT MONO (-4950 1425);
DISPLAY INVISIBLE (-4950 1425);
FORCEADD CAD_NOTE..1
(1075 5200);
FORCEPROP 0 LAST L1 PLACE RESISTORS CLOSE TO PCH
J 0
(950 5050);
DISPLAY 1.021277 (950 5050);
PAINT ORANGE (950 5050);
FORCEPROP 1 LAST COMMENT_BODY TRUE
J 0
(1100 5300);
DISPLAY 0.978723 (1100 5300);
PAINT ORANGE (1100 5300);
DISPLAY INVISIBLE (1100 5300);
FORCEPROP 2 LAST CDS_LIB mstr_symbols
J 0
(1075 5200);
PAINT ORANGE (1075 5200);
DISPLAY INVISIBLE (1075 5200);
FORCEADD DNS..2
(-3095 1320);
PAINT RED (-3095 1320);
FORCEPROP 2 LAST CDS_LIB mstr_misc
J 0
(-3095 1320);
PAINT ORANGE (-3095 1320);
DISPLAY INVISIBLE (-3095 1320);
FORCEPROP 1 LAST COMMENT_BODY TRUE
R 1
J 0
(-3020 1095);
DISPLAY 0.872340 (-3020 1095);
PAINT GREEN (-3020 1095);
DISPLAY INVISIBLE (-3020 1095);
FORCEADD CAD_NOTE..1
(-3475 1050);
FORCEPROP 0 LAST L2 RESISTORS ON THE SMB_OCP_FRU_STBY_LVC3_SDA/SCL SIDE
J 0
(-3625 900);
DISPLAY 0.808511 (-3625 900);
PAINT ORANGE (-3625 900);
FORCEPROP 0 LAST L1 RUN TRACES THROUGH PADS ON THESE
J 0
(-3625 950);
DISPLAY 0.808511 (-3625 950);
PAINT ORANGE (-3625 950);
FORCEPROP 1 LAST COMMENT_BODY TRUE
J 0
(-3450 1150);
DISPLAY 0.978723 (-3450 1150);
PAINT ORANGE (-3450 1150);
DISPLAY INVISIBLE (-3450 1150);
FORCEPROP 2 LAST CDS_LIB mstr_symbols
J 0
(-3475 1050);
PAINT MONO (-3475 1050);
DISPLAY INVISIBLE (-3475 1050);
FORCEADD CAD_NOTE..1
(-2200 5075);
FORCEPROP 0 LAST L1 PLACE RESISTORS CLOSE TO PCH
J 0
(-2325 4950);
DISPLAY 1.021277 (-2325 4950);
PAINT ORANGE (-2325 4950);
FORCEPROP 1 LAST COMMENT_BODY TRUE
J 0
(-2175 5175);
DISPLAY 0.978723 (-2175 5175);
PAINT ORANGE (-2175 5175);
DISPLAY INVISIBLE (-2175 5175);
FORCEPROP 2 LAST CDS_LIB mstr_symbols
J 0
(-2200 5075);
PAINT ORANGE (-2200 5075);
DISPLAY INVISIBLE (-2200 5075);
FORCEADD DNS..2
(-3095 1420);
PAINT RED (-3095 1420);
FORCEPROP 2 LAST CDS_LIB mstr_misc
J 0
(-3095 1420);
PAINT ORANGE (-3095 1420);
DISPLAY INVISIBLE (-3095 1420);
FORCEPROP 1 LAST COMMENT_BODY TRUE
R 1
J 0
(-3020 1195);
DISPLAY 0.872340 (-3020 1195);
PAINT GREEN (-3020 1195);
DISPLAY INVISIBLE (-3020 1195);
FORCEADD INTEL_CORP_BPAGE..1
(2650 500);
FORCEPROP 1 LAST CDS_CON_LAST_MODIFIED Tue Dec 01 11:52:02 2015
J 0
(1225 825);
PAINT ORANGE (1225 825);
DISPLAY INVISIBLE (1225 825);
FORCEPROP 1 LAST CUSTOM_TXT_CDS <CURRENT_DESIGN_SHEET> OF <TOTAL_DESIGN_SHEETS>
J 0
(2150 525);
PAINT GREEN (2150 525);
FORCEPROP 1 LAST CUSTOM_TXT_CDS <CON_LAST_MODIFIED>
J 0
(725 850);
PAINT GREEN (725 850);
FORCEPROP 2 LAST CUSTOM_TXT_CDS <XR_PAGE_TITLE>
J 0
(-5240 5750);
DISPLAY 0.638298 (-5240 5750);
PAINT PINK (-5240 5750);
DISPLAY INVISIBLE (-5240 5750);
FORCEPROP 1 LAST SCH_REV 2.420
J 0
(2400 650);
DISPLAY 0.978723 (2400 650);
PAINT YELLOW (2400 650);
FORCEPROP 1 LAST SCH_DEPT BESD
J 1
(-1800 600);
DISPLAY 1.212766 (-1800 600);
PAINT YELLOW (-1800 600);
FORCEPROP 1 LAST SCH_NUMBER H4694802
J 0
(1350 650);
DISPLAY 1.212766 (1350 650);
PAINT YELLOW (1350 650);
FORCEPROP 1 LAST SCH_ADDRESS1 2200 Mission College Blvd.
J 0
(-1325 625);
DISPLAY 0.617021 (-1325 625);
PAINT GREEN (-1325 625);
FORCEPROP 1 LAST SCH_ADDRESS2 P.O. BOX 58119
J 0
(-1325 575);
DISPLAY 0.617021 (-1325 575);
PAINT GREEN (-1325 575);
FORCEPROP 1 LAST SCH_ADDRESS3 Santa Clara, CA 95052-8119
J 0
(-1325 525);
DISPLAY 0.617021 (-1325 525);
PAINT GREEN (-1325 525);
FORCEPROP 1 LAST SCH_TITLE LBG SMBUS RESISTORS
J 0
(-5300 550);
DISPLAY 1.212766 (-5300 550);
PAINT ORANGE (-5300 550);
FORCEPROP 2 LAST CDS_LIB mstr_symbols
J 0
(2650 500);
PAINT MONO (2650 500);
DISPLAY INVISIBLE (2650 500);
FORCEPROP 1 LAST COMMENT_BODY TRUE
J 0
(2662 512);
DISPLAY 0.468085 (2662 512);
PAINT GREEN (2662 512);
DISPLAY INVISIBLE (2662 512);
FORCEPROP 2 LAST BOM_COST SM_CONTROLLER
J 0
(-5225 5800);
PAINT MONO (-5225 5800);
DISPLAY INVISIBLE (-5225 5800);
FORCEPROP 2 LAST PAGE_BORDER TRUE
J 0
(-5240 5750);
DISPLAY 0.851064 (-5240 5750);
PAINT PINK (-5240 5750);
DISPLAY INVISIBLE (-5240 5750);
FORCEPROP 2 LAST CDS_XR_PAGE_TITLE CR-138 : @BASEBOARD_FAB2_LIB.BASEBOARD_FAB2(SCH_1):PAGE138
J 0
(-5240 5750);
DISPLAY 0.638298 (-5240 5750);
PAINT PINK (-5240 5750);
DISPLAY INVISIBLE (-5240 5750);
FORCEADD DESIGN_NOTE..1
(1450 3600);
FORCEPROP 0 LAST L1 PULL UPS FOR SENSOR BUS
J 0
(1250 3475);
DISPLAY 1.021277 (1250 3475);
PAINT ORANGE (1250 3475);
FORCEPROP 0 LAST L2 ON SEPARATE PAGE
J 0
(1250 3375);
DISPLAY 1.021277 (1250 3375);
PAINT ORANGE (1250 3375);
FORCEPROP 1 LAST COMMENT_BODY TRUE
J 0
(1475 3700);
DISPLAY 0.978723 (1475 3700);
PAINT ORANGE (1475 3700);
DISPLAY INVISIBLE (1475 3700);
FORCEPROP 2 LAST CDS_LIB mstr_symbols
J 0
(1450 3600);
PAINT ORANGE (1450 3600);
DISPLAY INVISIBLE (1450 3600);
FORCEADD CAD_NOTE..1
(-875 1025);
FORCEPROP 0 LAST L1 PLACE SMB RESISTORS NEAR PCH
J 0
(-1025 900);
DISPLAY 1.170213 (-1025 900);
PAINT WHITE (-1025 900);
FORCEPROP 1 LAST COMMENT_BODY TRUE
J 0
(-850 1125);
DISPLAY 1.595745 (-850 1125);
PAINT PEACH (-850 1125);
DISPLAY INVISIBLE (-850 1125);
FORCEPROP 2 LAST CDS_LIB mstr_symbols
J 0
(-875 1025);
PAINT ORANGE (-875 1025);
DISPLAY INVISIBLE (-875 1025);
WIRE 16 -1 (500 4550)(500 4675);
WIRE 16 -1 (850 4500)(850 4625);
WIRE 16 -1 (500 2675)(500 2775);
WIRE 16 -1 (875 2625)(875 2725);
WIRE 16 -1 (-3175 5050)(-3175 5150);
WIRE 16 -1 (-2775 5000)(-2775 5100);
WIRE 16 -1 (-3175 4125)(-3175 4200);
WIRE 16 -1 (-2775 4075)(-2775 4150);
WIRE 16 -1 (-3150 3050)(-3150 3150);
WIRE 16 -1 (-2750 3025)(-2750 3100);
WIRE 16 -1 (-3150 2200)(-3150 2250);
WIRE 16 -1 (-2750 2125)(-2750 2200);
WIRE 16 2175 (1175 2000)(1175 4975);
WIRE 16 2175 (-600 2000)(1175 2000);
WIRE 16 2175 (1175 4975)(-600 4975);
WIRE 16 2175 (-600 4975)(-600 2000);
WIRE 16 -1 (-1275 3225)(-375 3225);
WIRE 16 -1 (-1300 3050)(-375 3050);
WIRE 16 -1 (-1275 2275)(-375 2275);
WIRE 16 -1 (-1300 2125)(-375 2125);
WIRE 16 -1 (-175 3050)(1500 3050);
FORCEPROP 2 LAST SIG_NAME SMB_SENSOR_PCH_STBY_LVC3_SCL
J 2
(1525 3060);
DISPLAY 0.617021 (1525 3060);
PAINT ORANGE (1525 3060);
WIRE 16 -1 (1500 3225)(-175 3225);
FORCEPROP 2 LAST SIG_NAME SMB_SENSOR_PCH_STBY_LVC3_SDA
J 2
(1525 3235);
DISPLAY 0.617021 (1525 3235);
PAINT ORANGE (1525 3235);
WIRE 16 -1 (500 4350)(500 4150);
WIRE 16 -1 (1500 4150)(500 4150);
FORCEPROP 2 LAST SIG_NAME SMB_BMC_PMBUS_STBY_LVC3_SDA
J 2
(1525 4160);
DISPLAY 0.617021 (1525 4160);
PAINT ORANGE (1525 4160);
WIRE 16 -1 (850 4300)(850 4000);
WIRE 16 -1 (850 4000)(1500 4000);
FORCEPROP 2 LAST SIG_NAME SMB_BMC_PMBUS_STBY_LVC3_SCL
J 2
(1525 4010);
DISPLAY 0.617021 (1525 4010);
PAINT ORANGE (1525 4010);
WIRE 16 -1 (875 2425)(875 2125);
WIRE 16 -1 (1500 2125)(875 2125);
FORCEPROP 2 LAST SIG_NAME SMB_VR_STBY_LVC3_SCL
J 2
(1525 2135);
DISPLAY 0.617021 (1525 2135);
PAINT ORANGE (1525 2135);
WIRE 16 -1 (-175 2125)(875 2125);
WIRE 16 -1 (500 2475)(500 2275);
WIRE 16 -1 (1500 2275)(500 2275);
FORCEPROP 2 LAST SIG_NAME SMB_VR_STBY_LVC3_SDA
J 2
(1525 2285);
DISPLAY 0.617021 (1525 2285);
PAINT ORANGE (1525 2285);
WIRE 16 -1 (-175 2275)(500 2275);
WIRE 16 -1 (-2775 4800)(-2775 4475);
WIRE 16 -1 (-2200 4475)(-2775 4475);
FORCEPROP 2 LAST SIG_NAME SMB_SMLINK0_STBY_LVC3_SCL
J 2
(-2175 4485);
DISPLAY 0.617021 (-2175 4485);
PAINT ORANGE (-2175 4485);
WIRE 16 -1 (-3875 4475)(-2775 4475);
WIRE 16 2175 (-2400 1175)(-2400 5300);
WIRE 16 2175 (-4150 1175)(-2400 1175);
WIRE 16 2175 (-2400 5300)(-4150 5300);
WIRE 16 2175 (-4150 5300)(-4150 1175);
WIRE 16 -1 (-4775 4625)(-4075 4625);
FORCEPROP 2 LAST SIG_NAME SMB_SMLINK0_STBY_LVC3_SDA_R1
J 0
(-4800 4635);
DISPLAY 0.617021 (-4800 4635);
PAINT ORANGE (-4800 4635);
WIRE 16 -1 (-2775 3875)(-2775 3550);
WIRE 16 -1 (-2200 3550)(-2775 3550);
FORCEPROP 2 LAST SIG_NAME SMB_HOST_STBY_LVC3_SCL
J 2
(-2175 3560);
DISPLAY 0.617021 (-2175 3560);
PAINT ORANGE (-2175 3560);
WIRE 16 -1 (-3875 3550)(-2775 3550);
WIRE 16 -1 (-3175 3925)(-3175 3700);
WIRE 16 -1 (-2200 3700)(-3175 3700);
FORCEPROP 2 LAST SIG_NAME SMB_HOST_STBY_LVC3_SDA
J 2
(-2175 3710);
DISPLAY 0.617021 (-2175 3710);
PAINT ORANGE (-2175 3710);
WIRE 16 -1 (-3875 3700)(-3175 3700);
WIRE 16 -1 (-3150 2850)(-3150 2650);
WIRE 16 -1 (-2175 2650)(-3150 2650);
FORCEPROP 2 LAST SIG_NAME SMB_SLOTX24_PCH_STBY_LVC3_SDA
J 2
(-2150 2660);
DISPLAY 0.617021 (-2150 2660);
PAINT ORANGE (-2150 2660);
WIRE 16 -1 (-3850 2650)(-3150 2650);
WIRE 16 -1 (-3150 2000)(-3150 1775);
WIRE 16 -1 (-2175 1775)(-3150 1775);
FORCEPROP 2 LAST SIG_NAME SMB_LAN_STBY_LVC3_SDA
J 2
(-2150 1785);
DISPLAY 0.617021 (-2150 1785);
PAINT ORANGE (-2150 1785);
WIRE 16 -1 (-3400 1775)(-3150 1775);
WIRE 16 -1 (-3550 1775)(-3400 1775);
WIRE 16 -1 (-3400 1425)(-3400 1775);
WIRE 16 -1 (-3400 1425)(-3200 1425);
WIRE 16 -1 (-3550 2150)(-3550 1775);
WIRE 16 -1 (-3850 1775)(-3550 1775);
WIRE 16 -1 (-3550 2150)(-3875 2150);
WIRE 16 -1 (-2750 2825)(-2750 2500);
WIRE 16 -1 (-2175 2500)(-2750 2500);
FORCEPROP 2 LAST SIG_NAME SMB_SLOTX24_PCH_STBY_LVC3_SCL
J 2
(-2150 2510);
DISPLAY 0.617021 (-2150 2510);
PAINT ORANGE (-2150 2510);
WIRE 16 -1 (-3850 2500)(-2750 2500);
WIRE 16 -1 (-2200 4625)(-3175 4625);
FORCEPROP 2 LAST SIG_NAME SMB_SMLINK0_STBY_LVC3_SDA
J 2
(-2175 4635);
DISPLAY 0.617021 (-2175 4635);
PAINT ORANGE (-2175 4635);
WIRE 16 -1 (-3175 4625)(-3175 4850);
WIRE 16 -1 (-3875 4625)(-3175 4625);
WIRE 16 -1 (-3000 1425)(-2175 1425);
FORCEPROP 2 LAST SIG_NAME SMB_OCP_FRU_STBY_LVC3_SDA
J 0
(-2685 1435);
DISPLAY 0.617021 (-2685 1435);
PAINT ORANGE (-2685 1435);
WIRE 16 -1 (-3000 1325)(-2175 1325);
FORCEPROP 2 LAST SIG_NAME SMB_OCP_FRU_STBY_LVC3_SCL
J 0
(-2685 1335);
DISPLAY 0.617021 (-2685 1335);
PAINT ORANGE (-2685 1335);
WIRE 16 -1 (-2750 1625)(-2175 1625);
FORCEPROP 2 LAST SIG_NAME SMB_LAN_STBY_LVC3_SCL
J 2
(-2150 1635);
DISPLAY 0.617021 (-2150 1635);
PAINT ORANGE (-2150 1635);
WIRE 16 -1 (-2750 1925)(-2750 1625);
WIRE 16 -1 (-3525 1625)(-2750 1625);
WIRE 16 -1 (-3525 1325)(-3525 1625);
WIRE 16 -1 (-3700 1625)(-3525 1625);
WIRE 16 -1 (-3700 2000)(-3700 1625);
WIRE 16 -1 (-3850 1625)(-3700 1625);
WIRE 16 -1 (-3525 1325)(-3200 1325);
WIRE 16 -1 (-3875 2000)(-3700 2000);
WIRE 16 -1 (-4800 4475)(-4075 4475);
FORCEPROP 2 LAST SIG_NAME SMB_SMLINK0_STBY_LVC3_SCL_R1
J 0
(-4800 4485);
DISPLAY 0.617021 (-4800 4485);
PAINT ORANGE (-4800 4485);
WIRE 16 -1 (-4775 3700)(-4075 3700);
WIRE 16 -1 (-4800 3550)(-4075 3550);
FORCEPROP 2 LAST SIG_NAME SMB_HOST_STBY_LVC3_SCL_R1
J 0
(-4800 3560);
DISPLAY 0.617021 (-4800 3560);
PAINT ORANGE (-4800 3560);
WIRE 16 -1 (-4750 2650)(-4050 2650);
WIRE 16 -1 (-4775 2500)(-4050 2500);
WIRE 16 -1 (-4775 1625)(-4050 1625);
WIRE 16 -1 (-4750 1775)(-4050 1775);
FORCEPROP 2 LAST SIG_NAME SMB_LAN_STBY_LVC3_SDA_R1
J 0
(-4775 1785);
DISPLAY 0.617021 (-4775 1785);
PAINT ORANGE (-4775 1785);
WIRE 16 -1 (-4800 2000)(-4075 2000);
WIRE 16 -1 (-4775 2150)(-4075 2150);
FORCEPROP 2 LAST SIG_NAME SMB_LAN_STBY_LVC3_SDA_R2
J 0
(-4800 2160);
DISPLAY 0.617021 (-4800 2160);
PAINT ORANGE (-4800 2160);
DOT 1 (875 2125);
DOT 1 (500 2275);
DOT 1 (-2775 4475);
DOT 1 (-3175 4625);
DOT 1 (-2775 3550);
DOT 1 (-2750 2500);
DOT 1 (-3175 3700);
DOT 1 (-3150 2650);
DOT 1 (-2750 1625);
DOT 1 (-3150 1775);
DOT 1 (-3400 1775);
DOT 1 (-3550 1775);
DOT 1 (-3525 1625);
DOT 1 (-3700 1625);
FORCENOTE
OPTION 1120
(1150 3800) 0;
DISPLAY LEFT (1150 3800);
DISPLAY 1.021277 (1150 3800);
PAINT RED (1150 3800);
FORCENOTE
BOM_COST=SM_CONTROLLER
(-5175 650) 0;
DISPLAY LEFT (-5175 650);
DISPLAY 1.021277 (-5175 650);
PAINT PURPLE (-5175 650);
FORCENOTE
ROOM=SMBUS
(-5175 700) 0;
DISPLAY LEFT (-5175 700);
DISPLAY 1.021277 (-5175 700);
PAINT PURPLE (-5175 700);
QUIT
